FILE_TYPE = MACRO_DRAWING;
SET COLOR_WIRE YELLOW;
SET COLOR_PROP ORANGE;
SET COLOR_DOT WHITE;
SET COLOR_ARC YELLOW;
SET COLOR_BODY GREEN;
SET COLOR_NOTE PURPLE;
SET PROP_DISPLAY VALUE;
SET PAGE_NUMBER P184;
FORCEADD UNIVERSAL_GND..1
(-9225 3825);
FORCEPROP 3 LASTPIN (-9225 3875) SIG_NAME GND\g
J 0
(-9215 3885);
DISPLAY 0.659574 (-9215 3885);
PAINT MONO (-9215 3885);
DISPLAY INVISIBLE (-9215 3885);
FORCEPROP 2 LAST CDS_LIB pure_quanta_power
J 0
(-9225 3825);
DISPLAY INVISIBLE (-9225 3825);
FORCEPROP 1 LAST HDL_POWER GND
J 1
(-9200 3750);
DISPLAY 0.872340 (-9200 3750);
PAINT GREEN (-9200 3750);
DISPLAY INVISIBLE (-9200 3750);
FORCEPROP 1 LAST PATH I1
J 0
(-9150 3825);
DISPLAY 0.872340 (-9150 3825);
PAINT AQUA (-9150 3825);
DISPLAY INVISIBLE (-9150 3825);
FORCEADD UNIVERSAL_GND..1
(-7575 2325);
FORCEPROP 3 LASTPIN (-7575 2375) SIG_NAME GND\g
J 0
(-7565 2385);
DISPLAY 0.659574 (-7565 2385);
PAINT MONO (-7565 2385);
DISPLAY INVISIBLE (-7565 2385);
FORCEPROP 2 LAST CDS_LIB pure_quanta_power
J 0
(-7575 2325);
DISPLAY INVISIBLE (-7575 2325);
FORCEPROP 1 LAST HDL_POWER GND
J 1
(-7550 2250);
DISPLAY 0.872340 (-7550 2250);
PAINT GREEN (-7550 2250);
DISPLAY INVISIBLE (-7550 2250);
FORCEPROP 1 LAST PATH I10
J 0
(-7500 2325);
DISPLAY 0.872340 (-7500 2325);
PAINT AQUA (-7500 2325);
DISPLAY INVISIBLE (-7500 2325);
FORCEADD Q_CAP..1
R 2
(-7575 2550);
FORCEPROP 1 LAST LOCATION PC212
J 0
(-7525 2690);
DISPLAY 0.489362 (-7525 2690);
PAINT SKYBLUE (-7525 2690);
FORCEPROP 2 LAST SEC 1
J 0
(-7625 2746);
DISPLAY 0.680851 (-7625 2746);
PAINT MONO (-7625 2746);
DISPLAY INVISIBLE (-7625 2746);
FORCEPROP 1 LASTPIN (-7575 2650) $PN 1
J 2
(-7529 2621);
DISPLAY 0.489362 (-7529 2621);
FORCEPROP 1 LASTPIN (-7575 2450) $PN 2
J 2
(-7531 2445);
DISPLAY 0.489362 (-7531 2445);
FORCEPROP 1 LAST TOLERANCE 10%
J 0
(-7525 2530);
DISPLAY 0.489362 (-7525 2530);
PAINT SKYBLUE (-7525 2530);
FORCEPROP 1 LAST VOLTAGE 25V
J 0
(-7525 2579);
DISPLAY 0.489362 (-7525 2579);
PAINT SKYBLUE (-7525 2579);
FORCEPROP 1 LAST PACK_TYPE C0402
J 0
(-7525 2432);
DISPLAY 0.489362 (-7525 2432);
PAINT SKYBLUE (-7525 2432);
FORCEPROP 1 LAST VALUE 1UF
J 0
(-7525 2628);
DISPLAY 0.489362 (-7525 2628);
PAINT SKYBLUE (-7525 2628);
FORCEPROP 1 LAST MATERIAL X6S
J 0
(-7525 2481);
DISPLAY 0.489362 (-7525 2481);
PAINT SKYBLUE (-7525 2481);
FORCEPROP 2 LAST CDS_LIB pure_quanta
J 0
(-7575 2550);
DISPLAY INVISIBLE (-7575 2550);
FORCEPROP 2 LAST SIGNAL_MODEL DEFAULT_CAPACITOR_100000PF_2_1
R 3
J 1
(-7645 2498);
DISPLAY 0.744681 (-7645 2498);
PAINT MONO (-7645 2498);
DISPLAY INVISIBLE (-7645 2498);
FORCEPROP 2 LAST SEC_TYPE C0402
J 0
(-7625 2746);
DISPLAY 1.021277 (-7625 2746);
DISPLAY INVISIBLE (-7625 2746);
FORCEPROP 1 LAST PATH I11
J 2
(-7625 2700);
DISPLAY 0.978723 (-7625 2700);
PAINT WHITE (-7625 2700);
DISPLAY INVISIBLE (-7625 2700);
FORCEPROP 1 LAST PART_NUMBER CH5104KEB02
J 0
(-7525 2383);
DISPLAY 0.489362 (-7525 2383);
PAINT SKYBLUE (-7525 2383);
DISPLAY INVISIBLE (-7525 2383);
FORCEADD Q_RES..2
(-7575 2975);
FORCEPROP 1 LAST LOCATION PR477
J 0
(-7530 3100);
DISPLAY 0.489362 (-7530 3100);
PAINT SKYBLUE (-7530 3100);
FORCEPROP 0 LAST $SEC 1
J 0
(-7525 3150);
DISPLAY 0.680851 (-7525 3150);
PAINT MONO (-7525 3150);
DISPLAY INVISIBLE (-7525 3150);
FORCEPROP 0 LAST CDS_SEC 1
J 0
(-7525 3150);
DISPLAY 1.021277 (-7525 3150);
DISPLAY INVISIBLE (-7525 3150);
FORCEPROP 1 LASTPIN (-7575 3075) $PN 1
J 0
(-7570 3037);
DISPLAY 0.489362 (-7570 3037);
PAINT MONO (-7570 3037);
FORCEPROP 1 LASTPIN (-7575 2875) $PN 2
J 0
(-7570 2885);
DISPLAY 0.489362 (-7570 2885);
PAINT MONO (-7570 2885);
FORCEPROP 1 LAST WATTAGE 1/16W
J 0
(-7535 2950);
DISPLAY 0.489362 (-7535 2950);
PAINT SKYBLUE (-7535 2950);
FORCEPROP 1 LAST MATERIAL CHIP
J 0
(-7535 2900);
DISPLAY 0.489362 (-7535 2900);
PAINT SKYBLUE (-7535 2900);
FORCEPROP 1 LAST TOLERANCE 5%
J 0
(-7530 3000);
DISPLAY 0.489362 (-7530 3000);
PAINT SKYBLUE (-7530 3000);
FORCEPROP 1 LAST VALUE 0
J 0
(-7530 3050);
DISPLAY 0.489362 (-7530 3050);
PAINT SKYBLUE (-7530 3050);
FORCEPROP 1 LAST PACK_TYPE 0402LF
J 0
(-7535 2800);
DISPLAY 0.489362 (-7535 2800);
PAINT SKYBLUE (-7535 2800);
FORCEPROP 2 LAST CDS_LIB pure_quanta
J 0
(-7575 2975);
DISPLAY INVISIBLE (-7575 2975);
FORCEPROP 1 LAST PATH I12
J 0
(-7525 3150);
DISPLAY 0.978723 (-7525 3150);
PAINT WHITE (-7525 3150);
DISPLAY INVISIBLE (-7525 3150);
FORCEPROP 1 LAST PART_NUMBER CS00002JB13
J 0
(-7535 2850);
DISPLAY 0.489362 (-7535 2850);
PAINT SKYBLUE (-7535 2850);
DISPLAY INVISIBLE (-7535 2850);
FORCEADD UNIVERSAL_GND..1
(-7950 3750);
FORCEPROP 3 LASTPIN (-7950 3800) SIG_NAME GND\g
J 0
(-7940 3810);
DISPLAY 0.659574 (-7940 3810);
PAINT MONO (-7940 3810);
DISPLAY INVISIBLE (-7940 3810);
FORCEPROP 2 LAST CDS_LIB pure_quanta_power
J 0
(-7950 3750);
DISPLAY INVISIBLE (-7950 3750);
FORCEPROP 1 LAST HDL_POWER GND
J 1
(-7925 3675);
DISPLAY 0.872340 (-7925 3675);
PAINT GREEN (-7925 3675);
DISPLAY INVISIBLE (-7925 3675);
FORCEPROP 1 LAST PATH I13
J 0
(-7875 3750);
DISPLAY 0.872340 (-7875 3750);
PAINT AQUA (-7875 3750);
DISPLAY INVISIBLE (-7875 3750);
FORCEADD UNIVERSAL_POWER..1
(-7575 3175);
FORCEPROP 3 LASTPIN (-7575 3125) SIG_NAME P3V3_AUX\g
J 0
(-7565 3135);
DISPLAY 0.659574 (-7565 3135);
PAINT MONO (-7565 3135);
DISPLAY INVISIBLE (-7565 3135);
FORCEPROP 1 LAST HDL_POWER P3V3_AUX
J 1
(-7575 3225);
DISPLAY 0.489362 (-7575 3225);
PAINT GREEN (-7575 3225);
FORCEPROP 2 LAST CDS_LIB mstr_symbols
J 0
(-7575 3175);
PAINT MONO (-7575 3175);
DISPLAY INVISIBLE (-7575 3175);
FORCEPROP 1 LAST PATH I14
J 0
(-7525 3200);
DISPLAY 0.872340 (-7525 3200);
PAINT AQUA (-7525 3200);
DISPLAY INVISIBLE (-7525 3200);
FORCEADD Q_RES..1
(-7075 3375);
FORCEPROP 1 LAST LOCATION PR417
J 0
(-7100 3425);
DISPLAY 0.489362 (-7100 3425);
PAINT SKYBLUE (-7100 3425);
FORCEPROP 0 LAST $SEC 1
J 0
(-7125 3450);
DISPLAY 0.680851 (-7125 3450);
PAINT MONO (-7125 3450);
DISPLAY INVISIBLE (-7125 3450);
FORCEPROP 0 LAST CDS_SEC 1
J 0
(-7125 3450);
DISPLAY 1.021277 (-7125 3450);
DISPLAY INVISIBLE (-7125 3450);
FORCEPROP 1 LASTPIN (-7175 3375) $PN 1
J 0
(-7163 3387);
DISPLAY 0.489362 (-7163 3387);
PAINT MONO (-7163 3387);
FORCEPROP 1 LASTPIN (-6975 3375) $PN 2
J 0
(-7013 3387);
DISPLAY 0.489362 (-7013 3387);
PAINT MONO (-7013 3387);
FORCEPROP 1 LAST PACK_TYPE 0402LF
J 0
(-7000 3300);
DISPLAY 0.489362 (-7000 3300);
PAINT SKYBLUE (-7000 3300);
FORCEPROP 1 LAST WATTAGE 1/16W
J 0
(-7000 3275);
DISPLAY 0.489362 (-7000 3275);
PAINT SKYBLUE (-7000 3275);
FORCEPROP 1 LAST MATERIAL CHIP
J 0
(-7375 3275);
DISPLAY 0.489362 (-7375 3275);
PAINT SKYBLUE (-7375 3275);
FORCEPROP 1 LAST TOLERANCE 5%
J 0
(-6950 3400);
DISPLAY 0.489362 (-6950 3400);
PAINT SKYBLUE (-6950 3400);
FORCEPROP 1 LAST VALUE 0
J 2
(-7250 3400);
DISPLAY 0.489362 (-7250 3400);
PAINT SKYBLUE (-7250 3400);
FORCEPROP 2 LAST CDS_LIB pure_quanta
J 0
(-7075 3375);
DISPLAY INVISIBLE (-7075 3375);
FORCEPROP 1 LAST PATH I15
J 0
(-7125 3525);
DISPLAY 0.978723 (-7125 3525);
PAINT WHITE (-7125 3525);
DISPLAY INVISIBLE (-7125 3525);
FORCEPROP 1 LAST PART_NUMBER CS00002JB13
J 0
(-7375 3300);
DISPLAY 0.489362 (-7375 3300);
PAINT SKYBLUE (-7375 3300);
DISPLAY INVISIBLE (-7375 3300);
FORCEADD UNIVERSAL_GND..1
(-6700 2300);
FORCEPROP 3 LASTPIN (-6700 2350) SIG_NAME GND\g
J 0
(-6690 2360);
DISPLAY 0.659574 (-6690 2360);
PAINT MONO (-6690 2360);
DISPLAY INVISIBLE (-6690 2360);
FORCEPROP 2 LAST CDS_LIB pure_quanta_power
J 0
(-6700 2300);
DISPLAY INVISIBLE (-6700 2300);
FORCEPROP 1 LAST HDL_POWER GND
J 1
(-6675 2225);
DISPLAY 0.872340 (-6675 2225);
PAINT GREEN (-6675 2225);
DISPLAY INVISIBLE (-6675 2225);
FORCEPROP 1 LAST PATH I16
J 0
(-6625 2300);
DISPLAY 0.872340 (-6625 2300);
PAINT AQUA (-6625 2300);
DISPLAY INVISIBLE (-6625 2300);
FORCEADD Q_RES..2
(-6700 2550);
FORCEPROP 1 LAST LOCATION PR448
J 0
(-6655 2675);
DISPLAY 0.489362 (-6655 2675);
PAINT SKYBLUE (-6655 2675);
FORCEPROP 2 LAST SEC 1
J 0
(-6638 2793);
DISPLAY 0.680851 (-6638 2793);
PAINT MONO (-6638 2793);
DISPLAY INVISIBLE (-6638 2793);
FORCEPROP 1 LASTPIN (-6700 2650) $PN 1
J 0
(-6695 2612);
DISPLAY 0.489362 (-6695 2612);
FORCEPROP 1 LASTPIN (-6700 2450) $PN 2
J 0
(-6695 2460);
DISPLAY 0.489362 (-6695 2460);
FORCEPROP 1 LAST WATTAGE 1/16W
J 0
(-6660 2525);
DISPLAY 0.489362 (-6660 2525);
PAINT SKYBLUE (-6660 2525);
FORCEPROP 1 LAST MATERIAL CHIP
J 0
(-6660 2475);
DISPLAY 0.489362 (-6660 2475);
PAINT SKYBLUE (-6660 2475);
FORCEPROP 1 LAST TOLERANCE 1%
J 0
(-6655 2575);
DISPLAY 0.489362 (-6655 2575);
PAINT SKYBLUE (-6655 2575);
FORCEPROP 1 LAST VALUE 8.66K
J 0
(-6655 2625);
DISPLAY 0.489362 (-6655 2625);
PAINT SKYBLUE (-6655 2625);
FORCEPROP 1 LAST PACK_TYPE 0402LF
J 0
(-6660 2375);
DISPLAY 0.489362 (-6660 2375);
PAINT SKYBLUE (-6660 2375);
FORCEPROP 2 LAST CDS_LIB pure_quanta
R 3
J 0
(-6700 2550);
DISPLAY INVISIBLE (-6700 2550);
FORCEPROP 2 LAST SEC_TYPE 0402LF
J 0
(-6638 2793);
DISPLAY 1.021277 (-6638 2793);
DISPLAY INVISIBLE (-6638 2793);
FORCEPROP 1 LAST PATH I17
J 0
(-6650 2725);
DISPLAY 0.978723 (-6650 2725);
PAINT WHITE (-6650 2725);
DISPLAY INVISIBLE (-6650 2725);
FORCEPROP 1 LAST PART_NUMBER CS28662FB02
J 0
(-6660 2425);
DISPLAY 0.489362 (-6660 2425);
PAINT SKYBLUE (-6660 2425);
DISPLAY INVISIBLE (-6660 2425);
FORCEADD MPQ8633BGLEC838Z..1
(-5750 3400);
FORCEPROP 1 LAST LOCATION PU57
J 0
(-5997 4307);
DISPLAY 0.489362 (-5997 4307);
PAINT SKYBLUE (-5997 4307);
FORCEPROP 0 LAST $SEC 1
J 0
(-6000 4475);
DISPLAY 0.680851 (-6000 4475);
PAINT MONO (-6000 4475);
DISPLAY INVISIBLE (-6000 4475);
FORCEPROP 0 LAST CDS_SEC 1
J 0
(-6000 4475);
DISPLAY 1.021277 (-6000 4475);
DISPLAY INVISIBLE (-6000 4475);
FORCEPROP 0 LASTPIN (-5350 2725) $PN 2
J 0
(-5340 2735);
DISPLAY 0.489362 (-5340 2735);
PAINT MONO (-5340 2735);
FORCEPROP 0 LASTPIN (-5350 3875) $PN 1
J 0
(-5340 3885);
DISPLAY 0.489362 (-5340 3885);
PAINT MONO (-5340 3885);
FORCEPROP 0 LASTPIN (-6150 2775) $PN 3
J 2
(-6160 2785);
DISPLAY 0.489362 (-6160 2785);
PAINT MONO (-6160 2785);
FORCEPROP 0 LASTPIN (-6150 3575) $PN 8
J 2
(-6160 3585);
DISPLAY 0.489362 (-6160 3585);
PAINT MONO (-6160 3585);
FORCEPROP 0 LASTPIN (-5350 3125) $PN 7
J 0
(-5340 3135);
DISPLAY 0.489362 (-5340 3135);
PAINT MONO (-5340 3135);
FORCEPROP 0 LASTPIN (-6150 3375) $PN 4
J 2
(-6160 3385);
DISPLAY 0.489362 (-6160 3385);
PAINT MONO (-6160 3385);
FORCEPROP 0 LASTPIN (-5350 2775) $PN 11_18
J 0
(-5340 2785);
DISPLAY 0.489362 (-5340 2785);
PAINT MONO (-5340 2785);
FORCEPROP 0 LASTPIN (-5350 4075) $PN 9
J 0
(-5340 4085);
DISPLAY 0.489362 (-5340 4085);
PAINT MONO (-5340 4085);
FORCEPROP 0 LASTPIN (-5350 2975) $PN 6
J 0
(-5340 2985);
DISPLAY 0.489362 (-5340 2985);
PAINT MONO (-5340 2985);
FORCEPROP 0 LASTPIN (-5350 3575) $PN 20
J 0
(-5340 3585);
DISPLAY 0.489362 (-5340 3585);
PAINT MONO (-5340 3585);
FORCEPROP 0 LASTPIN (-5350 2875) $PN 5
J 0
(-5340 2885);
DISPLAY 0.489362 (-5340 2885);
PAINT MONO (-5340 2885);
FORCEPROP 0 LASTPIN (-6150 3125) $PN 19
J 2
(-6160 3135);
DISPLAY 0.489362 (-6160 3135);
PAINT MONO (-6160 3135);
FORCEPROP 0 LASTPIN (-6150 4075) $PN 10
J 2
(-6160 4085);
DISPLAY 0.489362 (-6160 4085);
PAINT MONO (-6160 4085);
FORCEPROP 0 LASTPIN (-6150 4025) $PN 21
J 2
(-6160 4035);
DISPLAY 0.489362 (-6160 4035);
PAINT MONO (-6160 4035);
FORCEPROP 1 LAST MATERIAL IC
J 0
(-5997 4129);
DISPLAY 0.489362 (-5997 4129);
PAINT SKYBLUE (-5997 4129);
FORCEPROP 2 LAST VALUE MPQ8633BGLE-C838-Z
J 0
(-6000 4375);
DISPLAY 0.489362 (-6000 4375);
PAINT SKYBLUE (-6000 4375);
FORCEPROP 2 LAST PART_TYPE SMLF
J 0
(-6000 4425);
DISPLAY 0.680851 (-6000 4425);
FORCEPROP 1 LAST CDS_LMAN_SYM_OUTLINE -250,725,250,-725
J 0
(-5750 3400);
DISPLAY 0.468085 (-5750 3400);
PAINT GREEN (-5750 3400);
DISPLAY INVISIBLE (-5750 3400);
FORCEPROP 1 LAST NEEDS_NO_SIZE TRUE
J 0
(-5750 3400);
DISPLAY 0.723404 (-5750 3400);
PAINT GREEN (-5750 3400);
DISPLAY INVISIBLE (-5750 3400);
FORCEPROP 2 LAST CDS_LIB pure_quanta
J 0
(-5750 3400);
DISPLAY INVISIBLE (-5750 3400);
FORCEPROP 1 LAST PATH I18
J 0
(-5750 3400);
DISPLAY 0.723404 (-5750 3400);
PAINT GREEN (-5750 3400);
DISPLAY INVISIBLE (-5750 3400);
FORCEPROP 1 LAST PART_NUMBER AL008633005
J 0
(-5997 4208);
DISPLAY 0.489362 (-5997 4208);
PAINT SKYBLUE (-5997 4208);
DISPLAY INVISIBLE (-5997 4208);
FORCEADD UNIVERSAL_GND..1
(-5125 2450);
FORCEPROP 3 LASTPIN (-5125 2500) SIG_NAME GND\g
J 0
(-5115 2510);
DISPLAY 0.659574 (-5115 2510);
PAINT MONO (-5115 2510);
DISPLAY INVISIBLE (-5115 2510);
FORCEPROP 2 LAST CDS_LIB pure_quanta_power
J 0
(-5125 2450);
DISPLAY INVISIBLE (-5125 2450);
FORCEPROP 1 LAST HDL_POWER GND
J 1
(-5100 2375);
DISPLAY 0.872340 (-5100 2375);
PAINT GREEN (-5100 2375);
DISPLAY INVISIBLE (-5100 2375);
FORCEPROP 1 LAST PATH I19
J 0
(-5050 2450);
DISPLAY 0.872340 (-5050 2450);
PAINT AQUA (-5050 2450);
DISPLAY INVISIBLE (-5050 2450);
FORCEADD OFFPAGE..1
(-8850 3575);
FORCEPROP 2 LAST $XR0 81 
J 0
(-9071 3575);
DISPLAY 0.638298 (-9071 3575);
PAINT MONO (-9071 3575);
FORCEPROP 2 LAST CDS_LIB standard
J 0
(-8850 3575);
DISPLAY INVISIBLE (-8850 3575);
FORCEPROP 1 LAST OFFPAGE TRUE
J 0
(-8525 3450);
DISPLAY 0.872340 (-8525 3450);
PAINT GREEN (-8525 3450);
DISPLAY INVISIBLE (-8525 3450);
FORCEPROP 1 LAST COMMENT_BODY TRUE
J 0
(-8725 3475);
DISPLAY 0.872340 (-8725 3475);
PAINT GREEN (-8725 3475);
DISPLAY INVISIBLE (-8725 3475);
FORCEPROP 2 LAST PATH I2
J 0
(-9050 3625);
DISPLAY 0.680851 (-9050 3625);
DISPLAY INVISIBLE (-9050 3625);
FORCEADD UNIVERSAL_GND..1
(-5000 2450);
FORCEPROP 3 LASTPIN (-5000 2500) SIG_NAME GND\g
J 0
(-4990 2510);
DISPLAY 0.659574 (-4990 2510);
PAINT MONO (-4990 2510);
DISPLAY INVISIBLE (-4990 2510);
FORCEPROP 2 LAST CDS_LIB pure_quanta_power
J 0
(-5000 2450);
DISPLAY INVISIBLE (-5000 2450);
FORCEPROP 1 LAST HDL_POWER GND
J 1
(-4975 2375);
DISPLAY 0.872340 (-4975 2375);
PAINT GREEN (-4975 2375);
DISPLAY INVISIBLE (-4975 2375);
FORCEPROP 1 LAST PATH I20
J 0
(-4925 2450);
DISPLAY 0.872340 (-4925 2450);
PAINT AQUA (-4925 2450);
DISPLAY INVISIBLE (-4925 2450);
FORCEADD Q_CAP..1
(-5000 2700);
FORCEPROP 1 LAST LOCATION PC258
J 0
(-4950 2775);
DISPLAY 0.489362 (-4950 2775);
PAINT SKYBLUE (-4950 2775);
FORCEPROP 0 LAST $SEC 1
J 0
(-4950 2825);
DISPLAY 0.680851 (-4950 2825);
PAINT MONO (-4950 2825);
DISPLAY INVISIBLE (-4950 2825);
FORCEPROP 2 LAST CDS_SEC 1
J 0
(-4950 2900);
DISPLAY 0.680851 (-4950 2900);
DISPLAY INVISIBLE (-4950 2900);
FORCEPROP 1 LASTPIN (-5000 2800) $PN 1
J 0
(-4990 2780);
DISPLAY 0.489362 (-4990 2780);
PAINT MONO (-4990 2780);
FORCEPROP 1 LASTPIN (-5000 2600) $PN 2
J 0
(-4990 2580);
DISPLAY 0.489362 (-4990 2580);
PAINT MONO (-4990 2580);
FORCEPROP 1 LAST VALUE 0.022UF
J 0
(-4950 2725);
DISPLAY 0.489362 (-4950 2725);
PAINT SKYBLUE (-4950 2725);
FORCEPROP 1 LAST MATERIAL X7R
J 0
(-4950 2575);
DISPLAY 0.489362 (-4950 2575);
PAINT SKYBLUE (-4950 2575);
FORCEPROP 1 LAST PACK_TYPE 0402
J 0
(-4950 2475);
DISPLAY 0.489362 (-4950 2475);
PAINT SKYBLUE (-4950 2475);
FORCEPROP 1 LAST VOLTAGE 25V
J 0
(-4950 2675);
DISPLAY 0.489362 (-4950 2675);
PAINT SKYBLUE (-4950 2675);
FORCEPROP 1 LAST TOLERANCE 10%
J 0
(-4950 2625);
DISPLAY 0.489362 (-4950 2625);
PAINT SKYBLUE (-4950 2625);
FORCEPROP 2 LAST CDS_LIB pure_quanta
J 0
(-5000 2700);
DISPLAY INVISIBLE (-5000 2700);
FORCEPROP 1 LAST PATH I21
J 0
(-4950 2850);
DISPLAY 0.978723 (-4950 2850);
PAINT WHITE (-4950 2850);
DISPLAY INVISIBLE (-4950 2850);
FORCEPROP 1 LAST PART_NUMBER CH3224K1B01
J 0
(-4950 2525);
DISPLAY 0.489362 (-4950 2525);
PAINT SKYBLUE (-4950 2525);
DISPLAY INVISIBLE (-4950 2525);
FORCEADD Q_CAP..1
R 1
(-4575 2875);
FORCEPROP 1 LAST LOCATION PC113
J 0
(-4625 2925);
DISPLAY 0.489362 (-4625 2925);
PAINT SKYBLUE (-4625 2925);
FORCEPROP 0 LAST $SEC 1
R 1
J 0
(-4575 2950);
DISPLAY 0.680851 (-4575 2950);
PAINT MONO (-4575 2950);
DISPLAY INVISIBLE (-4575 2950);
FORCEPROP 0 LAST CDS_SEC 1
R 1
J 0
(-4575 2950);
DISPLAY 1.021277 (-4575 2950);
DISPLAY INVISIBLE (-4575 2950);
FORCEPROP 1 LASTPIN (-4675 2875) $PN 1
R 1
J 0
(-4655 2885);
DISPLAY 0.489362 (-4655 2885);
PAINT MONO (-4655 2885);
FORCEPROP 1 LASTPIN (-4475 2875) $PN 2
R 1
J 0
(-4455 2885);
DISPLAY 0.489362 (-4455 2885);
PAINT MONO (-4455 2885);
FORCEPROP 1 LAST PACK_TYPE 0402
J 0
(-4525 2750);
DISPLAY 0.489362 (-4525 2750);
PAINT SKYBLUE (-4525 2750);
FORCEPROP 1 LAST TOLERANCE 10%
J 0
(-4700 2750);
DISPLAY 0.489362 (-4700 2750);
PAINT SKYBLUE (-4700 2750);
FORCEPROP 1 LAST MATERIAL X7R
J 0
(-4500 2800);
DISPLAY 0.489362 (-4500 2800);
PAINT SKYBLUE (-4500 2800);
FORCEPROP 1 LAST VALUE 0.1UF
J 0
(-4750 2900);
DISPLAY 0.489362 (-4750 2900);
PAINT SKYBLUE (-4750 2900);
FORCEPROP 1 LAST VOLTAGE 25V
J 0
(-4500 2925);
DISPLAY 0.489362 (-4500 2925);
PAINT SKYBLUE (-4500 2925);
FORCEPROP 2 LAST CDS_LIB pure_quanta
J 0
(-4575 2875);
DISPLAY INVISIBLE (-4575 2875);
FORCEPROP 1 LAST PATH I22
R 1
J 0
(-4725 2925);
DISPLAY 0.978723 (-4725 2925);
PAINT WHITE (-4725 2925);
DISPLAY INVISIBLE (-4725 2925);
FORCEPROP 1 LAST PART_NUMBER CH4104K1B00
J 0
(-4800 2800);
DISPLAY 0.489362 (-4800 2800);
PAINT SKYBLUE (-4800 2800);
DISPLAY INVISIBLE (-4800 2800);
FORCEADD Q_RES..2
(-4150 2600);
FORCEPROP 1 LAST LOCATION PR470
J 0
(-4105 2725);
DISPLAY 0.489362 (-4105 2725);
PAINT SKYBLUE (-4105 2725);
FORCEPROP 2 LAST $SEC 1
J 0
(-4100 2825);
DISPLAY 0.680851 (-4100 2825);
PAINT MONO (-4100 2825);
DISPLAY INVISIBLE (-4100 2825);
FORCEPROP 2 LAST CDS_SEC 1
J 0
(-4100 2825);
DISPLAY 0.680851 (-4100 2825);
DISPLAY INVISIBLE (-4100 2825);
FORCEPROP 1 LASTPIN (-4150 2700) $PN 1
J 0
(-4145 2662);
DISPLAY 0.489362 (-4145 2662);
FORCEPROP 1 LASTPIN (-4150 2500) $PN 2
J 0
(-4145 2510);
DISPLAY 0.489362 (-4145 2510);
FORCEPROP 1 LAST VALUE 10K
J 0
(-4105 2675);
DISPLAY 0.489362 (-4105 2675);
PAINT SKYBLUE (-4105 2675);
FORCEPROP 1 LAST MATERIAL CHIP
J 0
(-4110 2525);
DISPLAY 0.489362 (-4110 2525);
PAINT SKYBLUE (-4110 2525);
FORCEPROP 1 LAST TOLERANCE 1%
J 0
(-4105 2625);
DISPLAY 0.489362 (-4105 2625);
PAINT SKYBLUE (-4105 2625);
FORCEPROP 1 LAST WATTAGE 1/16W
J 0
(-4110 2575);
DISPLAY 0.489362 (-4110 2575);
PAINT SKYBLUE (-4110 2575);
FORCEPROP 1 LAST PACK_TYPE 0402LF
J 0
(-4110 2425);
DISPLAY 0.489362 (-4110 2425);
PAINT SKYBLUE (-4110 2425);
FORCEPROP 2 LAST CDS_LIB pure_quanta
J 0
(-4150 2600);
DISPLAY INVISIBLE (-4150 2600);
FORCEPROP 1 LAST PATH I23
J 0
(-4100 2775);
DISPLAY 0.978723 (-4100 2775);
PAINT WHITE (-4100 2775);
DISPLAY INVISIBLE (-4100 2775);
FORCEPROP 1 LAST PART_NUMBER CS31002FB08
J 0
(-4110 2475);
DISPLAY 0.489362 (-4110 2475);
PAINT SKYBLUE (-4110 2475);
DISPLAY INVISIBLE (-4110 2475);
FORCEADD Q_CAP..1
(-4100 3725);
FORCEPROP 1 LAST LOCATION PC209
J 0
(-4050 3900);
DISPLAY 0.489362 (-4050 3900);
PAINT SKYBLUE (-4050 3900);
FORCEPROP 2 LAST SEC 1
J 0
(-4026 3944);
DISPLAY 0.680851 (-4026 3944);
PAINT MONO (-4026 3944);
DISPLAY INVISIBLE (-4026 3944);
FORCEPROP 1 LASTPIN (-4100 3825) $PN 1
J 0
(-4090 3805);
DISPLAY 0.489362 (-4090 3805);
FORCEPROP 1 LASTPIN (-4100 3625) $PN 2
J 0
(-4090 3605);
DISPLAY 0.489362 (-4090 3605);
FORCEPROP 1 LAST PACK_TYPE 0402
J 0
(-4050 3600);
DISPLAY 0.489362 (-4050 3600);
PAINT SKYBLUE (-4050 3600);
FORCEPROP 1 LAST MATERIAL X7R
J 0
(-4050 3700);
DISPLAY 0.489362 (-4050 3700);
PAINT SKYBLUE (-4050 3700);
FORCEPROP 1 LAST VALUE 0.22UF
J 0
(-4050 3850);
DISPLAY 0.489362 (-4050 3850);
PAINT SKYBLUE (-4050 3850);
FORCEPROP 1 LAST VOLTAGE 16V
J 0
(-4050 3800);
DISPLAY 0.489362 (-4050 3800);
PAINT SKYBLUE (-4050 3800);
FORCEPROP 1 LAST TOLERANCE 10%
J 0
(-4050 3750);
DISPLAY 0.489362 (-4050 3750);
PAINT SKYBLUE (-4050 3750);
FORCEPROP 2 LAST SEC_TYPE 0402
J 0
(-4026 3944);
DISPLAY 1.021277 (-4026 3944);
DISPLAY INVISIBLE (-4026 3944);
FORCEPROP 2 LAST CDS_LIB pure_quanta
J 0
(-4100 3725);
PAINT MONO (-4100 3725);
DISPLAY INVISIBLE (-4100 3725);
FORCEPROP 1 LAST PATH I24
J 0
(-4050 3875);
DISPLAY 0.978723 (-4050 3875);
PAINT WHITE (-4050 3875);
DISPLAY INVISIBLE (-4050 3875);
FORCEPROP 1 LAST PART_NUMBER CH4223K1B00
J 0
(-4050 3650);
DISPLAY 0.489362 (-4050 3650);
PAINT SKYBLUE (-4050 3650);
DISPLAY INVISIBLE (-4050 3650);
FORCEADD Q_CAP..1
(-7575 4125);
FORCEPROP 1 LAST LOCATION PC227
J 0
(-7525 4225);
DISPLAY 0.489362 (-7525 4225);
PAINT SKYBLUE (-7525 4225);
FORCEPROP 0 LAST $SEC 1
J 0
(-7525 4250);
DISPLAY 0.680851 (-7525 4250);
PAINT MONO (-7525 4250);
DISPLAY INVISIBLE (-7525 4250);
FORCEPROP 0 LAST CDS_SEC 1
J 0
(-7525 4275);
DISPLAY 1.021277 (-7525 4275);
DISPLAY INVISIBLE (-7525 4275);
FORCEPROP 1 LASTPIN (-7575 4225) $PN 1
J 0
(-7565 4205);
DISPLAY 0.489362 (-7565 4205);
PAINT MONO (-7565 4205);
FORCEPROP 1 LASTPIN (-7575 4025) $PN 2
J 0
(-7565 4005);
DISPLAY 0.489362 (-7565 4005);
PAINT MONO (-7565 4005);
FORCEPROP 1 LAST PACK_TYPE C0805
J 0
(-7525 3925);
DISPLAY 0.489362 (-7525 3925);
PAINT SKYBLUE (-7525 3925);
FORCEPROP 1 LAST VOLTAGE 16V
J 0
(-7525 4125);
DISPLAY 0.489362 (-7525 4125);
PAINT SKYBLUE (-7525 4125);
FORCEPROP 1 LAST TOLERANCE 20%
J 0
(-7525 4075);
DISPLAY 0.489362 (-7525 4075);
PAINT SKYBLUE (-7525 4075);
FORCEPROP 1 LAST MATERIAL X6S
J 0
(-7525 4025);
DISPLAY 0.489362 (-7525 4025);
PAINT SKYBLUE (-7525 4025);
FORCEPROP 1 LAST VALUE 22UF
J 0
(-7525 4175);
DISPLAY 0.489362 (-7525 4175);
PAINT SKYBLUE (-7525 4175);
FORCEPROP 2 LAST CDS_LIB pure_quanta
J 0
(-7575 4125);
DISPLAY INVISIBLE (-7575 4125);
FORCEPROP 1 LAST PATH I25
J 0
(-7525 4275);
DISPLAY 0.978723 (-7525 4275);
PAINT WHITE (-7525 4275);
DISPLAY INVISIBLE (-7525 4275);
FORCEPROP 1 LAST PART_NUMBER CH6223MEA01
J 0
(-7525 3975);
DISPLAY 0.489362 (-7525 3975);
PAINT SKYBLUE (-7525 3975);
DISPLAY INVISIBLE (-7525 3975);
FORCEADD Q_CAP..1
(-7225 4125);
FORCEPROP 1 LAST LOCATION PC254
J 0
(-7175 4225);
DISPLAY 0.489362 (-7175 4225);
PAINT SKYBLUE (-7175 4225);
FORCEPROP 0 LAST $SEC 1
J 0
(-7175 4250);
DISPLAY 0.680851 (-7175 4250);
PAINT MONO (-7175 4250);
DISPLAY INVISIBLE (-7175 4250);
FORCEPROP 0 LAST CDS_SEC 1
J 0
(-7175 4275);
DISPLAY 1.021277 (-7175 4275);
DISPLAY INVISIBLE (-7175 4275);
FORCEPROP 1 LASTPIN (-7225 4225) $PN 1
J 0
(-7215 4205);
DISPLAY 0.489362 (-7215 4205);
PAINT MONO (-7215 4205);
FORCEPROP 1 LASTPIN (-7225 4025) $PN 2
J 0
(-7215 4005);
DISPLAY 0.489362 (-7215 4005);
PAINT MONO (-7215 4005);
FORCEPROP 1 LAST PACK_TYPE C0805
J 0
(-7175 3925);
DISPLAY 0.489362 (-7175 3925);
PAINT SKYBLUE (-7175 3925);
FORCEPROP 1 LAST MATERIAL X6S
J 0
(-7175 4025);
DISPLAY 0.489362 (-7175 4025);
PAINT SKYBLUE (-7175 4025);
FORCEPROP 1 LAST TOLERANCE 20%
J 0
(-7175 4075);
DISPLAY 0.489362 (-7175 4075);
PAINT SKYBLUE (-7175 4075);
FORCEPROP 1 LAST VOLTAGE 16V
J 0
(-7175 4125);
DISPLAY 0.489362 (-7175 4125);
PAINT SKYBLUE (-7175 4125);
FORCEPROP 1 LAST VALUE 22UF
J 0
(-7175 4175);
DISPLAY 0.489362 (-7175 4175);
PAINT SKYBLUE (-7175 4175);
FORCEPROP 2 LAST CDS_LIB pure_quanta
J 0
(-7225 4125);
DISPLAY INVISIBLE (-7225 4125);
FORCEPROP 1 LAST PATH I26
J 0
(-7175 4275);
DISPLAY 0.978723 (-7175 4275);
PAINT WHITE (-7175 4275);
DISPLAY INVISIBLE (-7175 4275);
FORCEPROP 1 LAST PART_NUMBER CH6223MEA01
J 0
(-7175 3975);
DISPLAY 0.489362 (-7175 3975);
PAINT SKYBLUE (-7175 3975);
DISPLAY INVISIBLE (-7175 3975);
FORCEADD Q_CAP..1
(-6975 4125);
FORCEPROP 1 LAST LOCATION PC81
J 0
(-6925 4225);
DISPLAY 0.489362 (-6925 4225);
PAINT SKYBLUE (-6925 4225);
FORCEPROP 0 LAST $SEC 1
J 0
(-6925 4250);
DISPLAY 0.680851 (-6925 4250);
PAINT MONO (-6925 4250);
DISPLAY INVISIBLE (-6925 4250);
FORCEPROP 0 LAST CDS_SEC 1
J 0
(-6925 4275);
DISPLAY 0.680851 (-6925 4275);
DISPLAY INVISIBLE (-6925 4275);
FORCEPROP 1 LASTPIN (-6975 4225) $PN 1
J 0
(-6965 4205);
DISPLAY 0.489362 (-6965 4205);
PAINT MONO (-6965 4205);
FORCEPROP 1 LASTPIN (-6975 4025) $PN 2
J 0
(-6965 4005);
DISPLAY 0.489362 (-6965 4005);
PAINT MONO (-6965 4005);
FORCEPROP 1 LAST PACK_TYPE C0805
J 0
(-6925 3925);
DISPLAY 0.489362 (-6925 3925);
PAINT SKYBLUE (-6925 3925);
FORCEPROP 1 LAST MATERIAL X6S
J 0
(-6925 4025);
DISPLAY 0.489362 (-6925 4025);
PAINT SKYBLUE (-6925 4025);
FORCEPROP 1 LAST VALUE 22UF
J 0
(-6925 4175);
DISPLAY 0.489362 (-6925 4175);
PAINT SKYBLUE (-6925 4175);
FORCEPROP 1 LAST VOLTAGE 16V
J 0
(-6925 4125);
DISPLAY 0.489362 (-6925 4125);
PAINT SKYBLUE (-6925 4125);
FORCEPROP 1 LAST TOLERANCE 20%
J 0
(-6925 4075);
DISPLAY 0.489362 (-6925 4075);
PAINT SKYBLUE (-6925 4075);
FORCEPROP 2 LAST CDS_LIB pure_quanta
J 0
(-6975 4125);
DISPLAY INVISIBLE (-6975 4125);
FORCEPROP 1 LAST PATH I27
J 0
(-6925 4275);
DISPLAY 0.978723 (-6925 4275);
PAINT WHITE (-6925 4275);
DISPLAY INVISIBLE (-6925 4275);
FORCEPROP 1 LAST PART_NUMBER CH6223MEA01
J 0
(-6925 3975);
DISPLAY 0.489362 (-6925 3975);
PAINT SKYBLUE (-6925 3975);
DISPLAY INVISIBLE (-6925 3975);
FORCEADD Q_CAP..1
(-6725 4125);
FORCEPROP 1 LAST LOCATION PC237
J 0
(-6675 4225);
DISPLAY 0.489362 (-6675 4225);
PAINT SKYBLUE (-6675 4225);
FORCEPROP 0 LAST $SEC 1
J 0
(-6675 4250);
DISPLAY 0.680851 (-6675 4250);
PAINT MONO (-6675 4250);
DISPLAY INVISIBLE (-6675 4250);
FORCEPROP 0 LAST CDS_SEC 1
J 0
(-6675 4250);
DISPLAY 1.021277 (-6675 4250);
DISPLAY INVISIBLE (-6675 4250);
FORCEPROP 1 LASTPIN (-6725 4225) $PN 1
J 0
(-6715 4205);
DISPLAY 0.489362 (-6715 4205);
PAINT MONO (-6715 4205);
FORCEPROP 1 LASTPIN (-6725 4025) $PN 2
J 0
(-6715 4005);
DISPLAY 0.489362 (-6715 4005);
PAINT MONO (-6715 4005);
FORCEPROP 1 LAST MATERIAL X6S
J 0
(-6675 4025);
DISPLAY 0.489362 (-6675 4025);
PAINT SKYBLUE (-6675 4025);
FORCEPROP 1 LAST PACK_TYPE C0402
J 0
(-6675 3925);
DISPLAY 0.489362 (-6675 3925);
PAINT SKYBLUE (-6675 3925);
FORCEPROP 1 LAST VALUE 1UF
J 0
(-6675 4175);
DISPLAY 0.489362 (-6675 4175);
PAINT SKYBLUE (-6675 4175);
FORCEPROP 1 LAST VOLTAGE 25V
J 0
(-6675 4125);
DISPLAY 0.489362 (-6675 4125);
PAINT SKYBLUE (-6675 4125);
FORCEPROP 1 LAST TOLERANCE 10%
J 0
(-6675 4075);
DISPLAY 0.489362 (-6675 4075);
PAINT SKYBLUE (-6675 4075);
FORCEPROP 2 LAST CDS_LIB pure_quanta
J 0
(-6725 4125);
PAINT MONO (-6725 4125);
DISPLAY INVISIBLE (-6725 4125);
FORCEPROP 1 LAST PATH I28
J 0
(-6675 4275);
DISPLAY 0.978723 (-6675 4275);
PAINT WHITE (-6675 4275);
DISPLAY INVISIBLE (-6675 4275);
FORCEPROP 1 LAST PART_NUMBER CH5104KEB02
J 0
(-6675 3975);
DISPLAY 0.489362 (-6675 3975);
PAINT SKYBLUE (-6675 3975);
DISPLAY INVISIBLE (-6675 3975);
FORCEADD Q_RES..2
(-4700 4375);
FORCEPROP 1 LAST LOCATION R8465
J 0
(-4655 4500);
DISPLAY 0.489362 (-4655 4500);
PAINT SKYBLUE (-4655 4500);
FORCEPROP 2 LAST SEC 1
J 0
(-4649 4604);
DISPLAY 0.680851 (-4649 4604);
PAINT MONO (-4649 4604);
DISPLAY INVISIBLE (-4649 4604);
FORCEPROP 1 LASTPIN (-4700 4475) $PN 1
J 0
(-4695 4437);
DISPLAY 0.489362 (-4695 4437);
FORCEPROP 1 LASTPIN (-4700 4275) $PN 2
J 0
(-4695 4285);
DISPLAY 0.489362 (-4695 4285);
FORCEPROP 1 LAST WATTAGE 1/16W
J 0
(-4660 4350);
DISPLAY 0.489362 (-4660 4350);
PAINT SKYBLUE (-4660 4350);
FORCEPROP 1 LAST VALUE 10K
J 0
(-4655 4450);
DISPLAY 0.489362 (-4655 4450);
PAINT SKYBLUE (-4655 4450);
FORCEPROP 1 LAST TOLERANCE 5%
J 0
(-4655 4400);
DISPLAY 0.489362 (-4655 4400);
PAINT SKYBLUE (-4655 4400);
FORCEPROP 1 LAST PACK_TYPE 0402LF
J 0
(-4660 4200);
DISPLAY 0.489362 (-4660 4200);
PAINT SKYBLUE (-4660 4200);
FORCEPROP 1 LAST MATERIAL CHIP
J 0
(-4660 4300);
DISPLAY 0.489362 (-4660 4300);
PAINT SKYBLUE (-4660 4300);
FORCEPROP 2 LAST CDS_LIB pure_quanta
R 3
J 0
(-4700 4375);
PAINT MONO (-4700 4375);
DISPLAY INVISIBLE (-4700 4375);
FORCEPROP 2 LAST SEC_TYPE 0402LF
J 0
(-4649 4604);
DISPLAY 1.021277 (-4649 4604);
DISPLAY INVISIBLE (-4649 4604);
FORCEPROP 1 LAST PATH I29
J 0
(-4650 4550);
DISPLAY 0.978723 (-4650 4550);
PAINT WHITE (-4650 4550);
DISPLAY INVISIBLE (-4650 4550);
FORCEPROP 1 LAST PART_NUMBER CS31002JB08
J 0
(-4660 4250);
DISPLAY 0.489362 (-4660 4250);
PAINT SKYBLUE (-4660 4250);
DISPLAY INVISIBLE (-4660 4250);
FORCEADD UNIVERSAL_GND..1
(-8575 3175);
FORCEPROP 3 LASTPIN (-8575 3225) SIG_NAME GND\g
J 0
(-8565 3235);
DISPLAY 0.659574 (-8565 3235);
PAINT MONO (-8565 3235);
DISPLAY INVISIBLE (-8565 3235);
FORCEPROP 2 LAST CDS_LIB pure_quanta_power
J 0
(-8575 3175);
DISPLAY INVISIBLE (-8575 3175);
FORCEPROP 1 LAST HDL_POWER GND
J 1
(-8550 3100);
DISPLAY 0.872340 (-8550 3100);
PAINT GREEN (-8550 3100);
DISPLAY INVISIBLE (-8550 3100);
FORCEPROP 1 LAST PATH I3
J 0
(-8500 3175);
DISPLAY 0.872340 (-8500 3175);
PAINT AQUA (-8500 3175);
DISPLAY INVISIBLE (-8500 3175);
FORCEADD UNIVERSAL_POWER..1
(-4700 4650);
FORCEPROP 3 LASTPIN (-4700 4600) SIG_NAME P3V3_AUX\g
J 0
(-4690 4610);
DISPLAY 0.659574 (-4690 4610);
PAINT MONO (-4690 4610);
DISPLAY INVISIBLE (-4690 4610);
FORCEPROP 1 LAST HDL_POWER P3V3_AUX
J 1
(-4700 4700);
DISPLAY 0.489362 (-4700 4700);
PAINT GREEN (-4700 4700);
FORCEPROP 2 LAST CDS_LIB mstr_symbols
J 0
(-4700 4650);
DISPLAY INVISIBLE (-4700 4650);
FORCEPROP 1 LAST PATH I30
J 0
(-4650 4675);
DISPLAY 0.872340 (-4650 4675);
PAINT AQUA (-4650 4675);
DISPLAY INVISIBLE (-4650 4675);
FORCEADD Q_RES..1
R 1
(-3575 1775);
FORCEPROP 1 LAST LOCATION PR418
J 0
(-3525 1950);
DISPLAY 0.489362 (-3525 1950);
PAINT SKYBLUE (-3525 1950);
FORCEPROP 0 LAST $SEC 1
R 1
J 0
(-3525 1975);
DISPLAY 0.680851 (-3525 1975);
PAINT MONO (-3525 1975);
DISPLAY INVISIBLE (-3525 1975);
FORCEPROP 0 LAST CDS_SEC 1
R 1
J 0
(-3525 1975);
DISPLAY 1.021277 (-3525 1975);
DISPLAY INVISIBLE (-3525 1975);
FORCEPROP 1 LASTPIN (-3575 1675) $PN 1
R 1
J 0
(-3587 1687);
DISPLAY 0.489362 (-3587 1687);
PAINT MONO (-3587 1687);
FORCEPROP 1 LASTPIN (-3575 1875) $PN 2
R 1
J 0
(-3587 1837);
DISPLAY 0.489362 (-3587 1837);
PAINT MONO (-3587 1837);
FORCEPROP 1 LAST TOLERANCE 1%
J 0
(-3525 1850);
DISPLAY 0.489362 (-3525 1850);
PAINT SKYBLUE (-3525 1850);
FORCEPROP 1 LAST VALUE 49.9
J 0
(-3525 1900);
DISPLAY 0.489362 (-3525 1900);
PAINT SKYBLUE (-3525 1900);
FORCEPROP 1 LAST PACK_TYPE 0402LF
J 0
(-3525 1650);
DISPLAY 0.489362 (-3525 1650);
PAINT SKYBLUE (-3525 1650);
FORCEPROP 1 LAST MATERIAL CHIP
J 0
(-3525 1750);
DISPLAY 0.489362 (-3525 1750);
PAINT SKYBLUE (-3525 1750);
FORCEPROP 1 LAST WATTAGE 1/16W
J 0
(-3525 1800);
DISPLAY 0.489362 (-3525 1800);
PAINT SKYBLUE (-3525 1800);
FORCEPROP 2 LAST CDS_LIB pure_quanta
J 0
(-3575 1775);
DISPLAY INVISIBLE (-3575 1775);
FORCEPROP 1 LAST PATH I31
R 1
J 0
(-3725 1725);
DISPLAY 0.978723 (-3725 1725);
PAINT WHITE (-3725 1725);
DISPLAY INVISIBLE (-3725 1725);
FORCEPROP 1 LAST PART_NUMBER CS04992FB07
J 0
(-3525 1700);
DISPLAY 0.489362 (-3525 1700);
PAINT SKYBLUE (-3525 1700);
DISPLAY INVISIBLE (-3525 1700);
FORCEADD UNIVERSAL_GND..1
(-3575 1525);
FORCEPROP 3 LASTPIN (-3575 1575) SIG_NAME GND\g
J 0
(-3565 1585);
DISPLAY 0.659574 (-3565 1585);
PAINT MONO (-3565 1585);
DISPLAY INVISIBLE (-3565 1585);
FORCEPROP 2 LAST CDS_LIB pure_quanta_power
J 0
(-3575 1525);
DISPLAY INVISIBLE (-3575 1525);
FORCEPROP 1 LAST HDL_POWER GND
J 1
(-3550 1450);
DISPLAY 0.872340 (-3550 1450);
PAINT GREEN (-3550 1450);
DISPLAY INVISIBLE (-3550 1450);
FORCEPROP 1 LAST PATH I32
J 0
(-3500 1525);
DISPLAY 0.872340 (-3500 1525);
PAINT AQUA (-3500 1525);
DISPLAY INVISIBLE (-3500 1525);
FORCEADD Q_CAP..2
(-3575 2800);
FORCEPROP 1 LAST LOCATION PC259
J 1
(-3575 2875);
DISPLAY 0.489362 (-3575 2875);
PAINT SKYBLUE (-3575 2875);
FORCEPROP 0 LAST $SEC 1
J 0
(-3575 2950);
DISPLAY 0.680851 (-3575 2950);
PAINT MONO (-3575 2950);
DISPLAY INVISIBLE (-3575 2950);
FORCEPROP 0 LAST CDS_SEC 1
J 0
(-3575 2950);
DISPLAY 0.680851 (-3575 2950);
DISPLAY INVISIBLE (-3575 2950);
FORCEPROP 1 LASTPIN (-3675 2800) $PN 1
J 0
(-3685 2815);
DISPLAY 0.489362 (-3685 2815);
PAINT MONO (-3685 2815);
FORCEPROP 1 LASTPIN (-3475 2800) $PN 2
J 0
(-3490 2815);
DISPLAY 0.489362 (-3490 2815);
PAINT MONO (-3490 2815);
FORCEPROP 1 LAST TOLERANCE 10%
J 2
(-3700 2675);
DISPLAY 0.489362 (-3700 2675);
PAINT SKYBLUE (-3700 2675);
FORCEPROP 1 LAST VOLTAGE 50V
J 0
(-3475 2850);
DISPLAY 0.489362 (-3475 2850);
PAINT SKYBLUE (-3475 2850);
FORCEPROP 1 LAST VALUE 220PF
J 2
(-3650 2850);
DISPLAY 0.489362 (-3650 2850);
PAINT SKYBLUE (-3650 2850);
FORCEPROP 1 LAST MATERIAL X7R
J 0
(-3500 2725);
DISPLAY 0.489362 (-3500 2725);
PAINT SKYBLUE (-3500 2725);
FORCEPROP 1 LAST PACK_TYPE 0402
J 1
(-3450 2675);
DISPLAY 0.489362 (-3450 2675);
PAINT SKYBLUE (-3450 2675);
FORCEPROP 2 LAST CDS_LIB pure_quanta
J 0
(-3575 2800);
DISPLAY INVISIBLE (-3575 2800);
FORCEPROP 1 LAST PATH I33
J 0
(-3575 3000);
DISPLAY 0.978723 (-3575 3000);
PAINT WHITE (-3575 3000);
DISPLAY INVISIBLE (-3575 3000);
FORCEPROP 1 LAST PART_NUMBER TMP_QCH12206KB14
J 1
(-3775 2725);
DISPLAY 0.489362 (-3775 2725);
PAINT SKYBLUE (-3775 2725);
DISPLAY INVISIBLE (-3775 2725);
FORCEADD Q_CAP..1
(-3150 2175);
FORCEPROP 1 LAST LOCATION PC6005
J 0
(-3100 2275);
DISPLAY 0.489362 (-3100 2275);
PAINT SKYBLUE (-3100 2275);
FORCEPROP 0 LAST $SEC 1
J 0
(-3100 2300);
DISPLAY 0.680851 (-3100 2300);
PAINT MONO (-3100 2300);
DISPLAY INVISIBLE (-3100 2300);
FORCEPROP 0 LAST CDS_SEC 1
J 0
(-3100 2300);
DISPLAY 0.680851 (-3100 2300);
DISPLAY INVISIBLE (-3100 2300);
FORCEPROP 1 LASTPIN (-3150 2275) $PN 1
J 0
(-3140 2255);
DISPLAY 0.787234 (-3140 2255);
PAINT MONO (-3140 2255);
FORCEPROP 1 LASTPIN (-3150 2075) $PN 2
J 0
(-3140 2055);
DISPLAY 0.787234 (-3140 2055);
PAINT MONO (-3140 2055);
FORCEPROP 1 LAST VALUE 0.01UF
J 0
(-3100 2225);
DISPLAY 0.489362 (-3100 2225);
PAINT SKYBLUE (-3100 2225);
FORCEPROP 1 LAST VOLTAGE 25V
J 0
(-3100 2175);
DISPLAY 0.489362 (-3100 2175);
PAINT SKYBLUE (-3100 2175);
FORCEPROP 1 LAST MATERIAL EMPTY
J 0
(-3275 2225);
DISPLAY 0.489362 (-3275 2225);
PAINT SKYBLUE (-3275 2225);
FORCEPROP 1 LAST TOLERANCE 10%
J 0
(-3100 2125);
DISPLAY 0.489362 (-3100 2125);
PAINT SKYBLUE (-3100 2125);
FORCEPROP 1 LAST PACK_TYPE C0402
J 0
(-3325 2125);
DISPLAY 0.489362 (-3325 2125);
PAINT SKYBLUE (-3325 2125);
FORCEPROP 2 LAST CDS_LIB pure_quanta
J 0
(-3150 2175);
DISPLAY INVISIBLE (-3150 2175);
FORCEPROP 1 LAST PATH I34
J 0
(-3100 2325);
DISPLAY 0.978723 (-3100 2325);
PAINT WHITE (-3100 2325);
DISPLAY INVISIBLE (-3100 2325);
FORCEPROP 1 LAST PART_NUMBER CH3104K1B11
J 0
(-3450 2175);
DISPLAY 0.489362 (-3450 2175);
PAINT SKYBLUE (-3450 2175);
DISPLAY INVISIBLE (-3450 2175);
FORCEADD Q_RES..1
(-3575 3125);
FORCEPROP 1 LAST LOCATION PR471
J 0
(-3625 3175);
DISPLAY 0.489362 (-3625 3175);
PAINT SKYBLUE (-3625 3175);
FORCEPROP 2 LAST $SEC 1
J 0
(-3602 3338);
DISPLAY 0.680851 (-3602 3338);
PAINT MONO (-3602 3338);
DISPLAY INVISIBLE (-3602 3338);
FORCEPROP 2 LAST CDS_SEC 1
J 0
(-3602 3338);
DISPLAY 0.680851 (-3602 3338);
DISPLAY INVISIBLE (-3602 3338);
FORCEPROP 1 LASTPIN (-3675 3125) $PN 1
J 0
(-3663 3137);
DISPLAY 0.489362 (-3663 3137);
FORCEPROP 1 LASTPIN (-3475 3125) $PN 2
J 0
(-3513 3137);
DISPLAY 0.489362 (-3513 3137);
FORCEPROP 1 LAST PACK_TYPE 0402LF
J 0
(-3400 3075);
DISPLAY 0.489362 (-3400 3075);
PAINT SKYBLUE (-3400 3075);
FORCEPROP 1 LAST MATERIAL CHIP
J 0
(-3400 3175);
DISPLAY 0.489362 (-3400 3175);
PAINT SKYBLUE (-3400 3175);
FORCEPROP 1 LAST VALUE 20K
J 2
(-3700 3175);
DISPLAY 0.489362 (-3700 3175);
PAINT SKYBLUE (-3700 3175);
FORCEPROP 2 LAST CDS_LIB pure_quanta
J 0
(-3575 3125);
DISPLAY INVISIBLE (-3575 3125);
FORCEPROP 1 LAST WATTAGE 1/16W
J 2
(-3001 3143);
DISPLAY 0.978723 (-3001 3143);
PAINT SKYBLUE (-3001 3143);
DISPLAY INVISIBLE (-3001 3143);
FORCEPROP 1 LAST TOLERANCE 1%
J 0
(-3455 3144);
DISPLAY 0.978723 (-3455 3144);
PAINT SKYBLUE (-3455 3144);
DISPLAY INVISIBLE (-3455 3144);
FORCEPROP 1 LAST PATH I35
J 0
(-3625 3275);
DISPLAY 0.978723 (-3625 3275);
PAINT WHITE (-3625 3275);
DISPLAY INVISIBLE (-3625 3275);
FORCEPROP 1 LAST PART_NUMBER CS32002FB06
J 0
(-3825 3075);
DISPLAY 0.489362 (-3825 3075);
PAINT SKYBLUE (-3825 3075);
DISPLAY INVISIBLE (-3825 3075);
FORCEADD Q_INDUCTOR..1
(-3575 3600);
FORCEPROP 1 LAST LOCATION PL78
J 0
(-3700 3760);
DISPLAY 0.489362 (-3700 3760);
PAINT SKYBLUE (-3700 3760);
FORCEPROP 2 LAST $SEC 1
J 0
(-3700 3900);
DISPLAY 0.680851 (-3700 3900);
PAINT MONO (-3700 3900);
DISPLAY INVISIBLE (-3700 3900);
FORCEPROP 2 LAST CDS_SEC 1
J 0
(-3700 3900);
DISPLAY 0.680851 (-3700 3900);
DISPLAY INVISIBLE (-3700 3900);
FORCEPROP 2 LASTPIN (-3675 3575) $PN 1
J 2
(-3685 3585);
DISPLAY 0.489362 (-3685 3585);
FORCEPROP 2 LASTPIN (-3475 3575) $PN 2
J 0
(-3465 3585);
DISPLAY 0.489362 (-3465 3585);
FORCEPROP 1 LAST MATERIAL IND
J 0
(-3700 3655);
DISPLAY 0.489362 (-3700 3655);
PAINT SKYBLUE (-3700 3655);
FORCEPROP 2 LAST PACK_TYPE SMLF
J 0
(-3700 3850);
DISPLAY 0.489362 (-3700 3850);
PAINT SKYBLUE (-3700 3850);
FORCEPROP 2 LAST VALUE 1.0UH/18A
J 0
(-3700 3800);
DISPLAY 0.489362 (-3700 3800);
PAINT SKYBLUE (-3700 3800);
FORCEPROP 1 LAST NEEDS_NO_SIZE TRUE
J 0
(-3575 3600);
DISPLAY 0.468085 (-3575 3600);
PAINT GREEN (-3575 3600);
DISPLAY INVISIBLE (-3575 3600);
FORCEPROP 2 LAST CDS_LIB pure_quanta
J 0
(-3575 3600);
DISPLAY INVISIBLE (-3575 3600);
FORCEPROP 1 LAST PATH I36
J 0
(-3500 3655);
DISPLAY 0.723404 (-3500 3655);
PAINT GREEN (-3500 3655);
DISPLAY INVISIBLE (-3500 3655);
FORCEPROP 1 LAST PART_NUMBER CV-10I0MZ01
J 0
(-3700 3710);
DISPLAY 0.489362 (-3700 3710);
PAINT SKYBLUE (-3700 3710);
DISPLAY INVISIBLE (-3700 3710);
FORCEADD Q_RES..2
R 1
(-2600 2025);
FORCEPROP 1 LAST LOCATION PR435
J 0
(-2600 2075);
DISPLAY 0.489362 (-2600 2075);
PAINT SKYBLUE (-2600 2075);
FORCEPROP 0 LAST $SEC 1
R 1
J 0
(-2475 2100);
DISPLAY 0.680851 (-2475 2100);
PAINT MONO (-2475 2100);
DISPLAY INVISIBLE (-2475 2100);
FORCEPROP 0 LAST CDS_SEC 1
R 1
J 0
(-2475 2100);
DISPLAY 1.021277 (-2475 2100);
DISPLAY INVISIBLE (-2475 2100);
FORCEPROP 1 LASTPIN (-2700 2025) $PN 1
R 1
J 0
(-2662 2030);
DISPLAY 0.489362 (-2662 2030);
PAINT MONO (-2662 2030);
FORCEPROP 1 LASTPIN (-2500 2025) $PN 2
R 1
J 0
(-2510 2030);
DISPLAY 0.489362 (-2510 2030);
PAINT MONO (-2510 2030);
FORCEPROP 1 LAST PACK_TYPE 0402LF
J 0
(-2500 1975);
DISPLAY 0.489362 (-2500 1975);
PAINT SKYBLUE (-2500 1975);
FORCEPROP 1 LAST WATTAGE 1/16W
J 0
(-2500 1925);
DISPLAY 0.489362 (-2500 1925);
PAINT SKYBLUE (-2500 1925);
FORCEPROP 1 LAST VALUE 0
R 2
J 0
(-2750 2075);
DISPLAY 0.489362 (-2750 2075);
PAINT SKYBLUE (-2750 2075);
FORCEPROP 1 LAST TOLERANCE 5%
J 0
(-2775 1925);
DISPLAY 0.489362 (-2775 1925);
PAINT SKYBLUE (-2775 1925);
FORCEPROP 1 LAST MATERIAL CHIP
J 0
(-2475 2075);
DISPLAY 0.489362 (-2475 2075);
PAINT SKYBLUE (-2475 2075);
FORCEPROP 2 LAST CDS_LIB pure_quanta
J 0
(-2600 2025);
DISPLAY INVISIBLE (-2600 2025);
FORCEPROP 1 LAST PATH I37
R 1
J 0
(-2775 2075);
DISPLAY 0.978723 (-2775 2075);
PAINT WHITE (-2775 2075);
DISPLAY INVISIBLE (-2775 2075);
FORCEPROP 1 LAST PART_NUMBER CS00002JB13
J 0
(-2875 1975);
DISPLAY 0.489362 (-2875 1975);
PAINT SKYBLUE (-2875 1975);
DISPLAY INVISIBLE (-2875 1975);
FORCEADD Q_RES..1
(-2600 2325);
FORCEPROP 1 LAST LOCATION PR434
J 0
(-2600 2375);
DISPLAY 0.489362 (-2600 2375);
PAINT SKYBLUE (-2600 2375);
FORCEPROP 0 LAST $SEC 1
J 0
(-2600 2400);
DISPLAY 0.680851 (-2600 2400);
PAINT MONO (-2600 2400);
DISPLAY INVISIBLE (-2600 2400);
FORCEPROP 0 LAST CDS_SEC 1
J 0
(-2600 2400);
DISPLAY 1.021277 (-2600 2400);
DISPLAY INVISIBLE (-2600 2400);
FORCEPROP 1 LASTPIN (-2700 2325) $PN 1
J 0
(-2688 2337);
DISPLAY 0.489362 (-2688 2337);
PAINT MONO (-2688 2337);
FORCEPROP 1 LASTPIN (-2500 2325) $PN 2
J 0
(-2538 2337);
DISPLAY 0.489362 (-2538 2337);
PAINT MONO (-2538 2337);
FORCEPROP 1 LAST VALUE 10
J 2
(-2725 2350);
DISPLAY 0.489362 (-2725 2350);
PAINT SKYBLUE (-2725 2350);
FORCEPROP 1 LAST TOLERANCE 1%
J 0
(-2775 2225);
DISPLAY 0.489362 (-2775 2225);
PAINT SKYBLUE (-2775 2225);
FORCEPROP 1 LAST MATERIAL CHIP
J 0
(-2400 2350);
DISPLAY 0.489362 (-2400 2350);
PAINT SKYBLUE (-2400 2350);
FORCEPROP 1 LAST PACK_TYPE 0402LF
J 0
(-2425 2275);
DISPLAY 0.489362 (-2425 2275);
PAINT SKYBLUE (-2425 2275);
FORCEPROP 1 LAST WATTAGE 1/16W
J 2
(-2300 2225);
DISPLAY 0.489362 (-2300 2225);
PAINT SKYBLUE (-2300 2225);
FORCEPROP 2 LAST CDS_LIB pure_quanta
J 0
(-2600 2325);
DISPLAY INVISIBLE (-2600 2325);
FORCEPROP 1 LAST PATH I38
J 0
(-2650 2475);
DISPLAY 0.978723 (-2650 2475);
PAINT WHITE (-2650 2475);
DISPLAY INVISIBLE (-2650 2475);
FORCEPROP 1 LAST PART_NUMBER CS01002FB07
J 0
(-2875 2275);
DISPLAY 0.489362 (-2875 2275);
PAINT SKYBLUE (-2875 2275);
DISPLAY INVISIBLE (-2875 2275);
FORCEADD Q_CAP..1
(-2925 3325);
FORCEPROP 1 LAST LOCATION PC114
J 0
(-2875 3425);
DISPLAY 0.489362 (-2875 3425);
PAINT SKYBLUE (-2875 3425);
FORCEPROP 0 LAST $SEC 1
J 0
(-2875 3450);
DISPLAY 0.680851 (-2875 3450);
PAINT MONO (-2875 3450);
DISPLAY INVISIBLE (-2875 3450);
FORCEPROP 0 LAST CDS_SEC 1
J 0
(-2875 3450);
DISPLAY 1.021277 (-2875 3450);
DISPLAY INVISIBLE (-2875 3450);
FORCEPROP 1 LASTPIN (-2925 3425) $PN 1
J 0
(-2915 3405);
DISPLAY 0.489362 (-2915 3405);
PAINT MONO (-2915 3405);
FORCEPROP 1 LASTPIN (-2925 3225) $PN 2
J 0
(-2915 3205);
DISPLAY 0.489362 (-2915 3205);
PAINT MONO (-2915 3205);
FORCEPROP 1 LAST MATERIAL X6S
J 0
(-2875 3225);
DISPLAY 0.489362 (-2875 3225);
PAINT SKYBLUE (-2875 3225);
FORCEPROP 1 LAST PACK_TYPE C0805
J 0
(-2875 3125);
DISPLAY 0.489362 (-2875 3125);
PAINT SKYBLUE (-2875 3125);
FORCEPROP 1 LAST TOLERANCE 20%
J 0
(-2875 3275);
DISPLAY 0.489362 (-2875 3275);
PAINT SKYBLUE (-2875 3275);
FORCEPROP 1 LAST VALUE 22UF
J 0
(-2875 3375);
DISPLAY 0.489362 (-2875 3375);
PAINT SKYBLUE (-2875 3375);
FORCEPROP 1 LAST VOLTAGE 4V
J 0
(-2875 3325);
DISPLAY 0.489362 (-2875 3325);
PAINT SKYBLUE (-2875 3325);
FORCEPROP 2 LAST CDS_LIB pure_quanta
J 0
(-2925 3325);
DISPLAY INVISIBLE (-2925 3325);
FORCEPROP 1 LAST PATH I39
J 0
(-2875 3475);
DISPLAY 0.978723 (-2875 3475);
PAINT WHITE (-2875 3475);
DISPLAY INVISIBLE (-2875 3475);
FORCEPROP 1 LAST PART_NUMBER CH622KMEA03
J 0
(-2875 3175);
DISPLAY 0.489362 (-2875 3175);
PAINT SKYBLUE (-2875 3175);
DISPLAY INVISIBLE (-2875 3175);
FORCEADD Q_CAP..1
R 2
(-8575 3375);
FORCEPROP 1 LAST LOCATION C674
J 2
(-8625 3475);
DISPLAY 0.489362 (-8625 3475);
PAINT SKYBLUE (-8625 3475);
FORCEPROP 0 LAST $SEC 1
J 0
(-8625 3525);
DISPLAY 0.680851 (-8625 3525);
PAINT MONO (-8625 3525);
DISPLAY INVISIBLE (-8625 3525);
FORCEPROP 0 LAST CDS_SEC 1
J 0
(-8625 3525);
DISPLAY 0.680851 (-8625 3525);
DISPLAY INVISIBLE (-8625 3525);
FORCEPROP 1 LASTPIN (-8575 3475) $PN 1
J 2
(-8585 3455);
DISPLAY 0.489362 (-8585 3455);
PAINT MONO (-8585 3455);
FORCEPROP 1 LASTPIN (-8575 3275) $PN 2
J 2
(-8585 3255);
DISPLAY 0.489362 (-8585 3255);
PAINT MONO (-8585 3255);
FORCEPROP 1 LAST MATERIAL EMPTY
J 2
(-8625 3275);
DISPLAY 0.489362 (-8625 3275);
PAINT RED (-8625 3275);
FORCEPROP 1 LAST TOLERANCE 10%
J 2
(-8625 3325);
DISPLAY 0.489362 (-8625 3325);
PAINT SKYBLUE (-8625 3325);
FORCEPROP 1 LAST PACK_TYPE 0402
J 2
(-8625 3175);
DISPLAY 0.489362 (-8625 3175);
PAINT SKYBLUE (-8625 3175);
FORCEPROP 1 LAST VALUE 0.1UF
J 2
(-8625 3425);
DISPLAY 0.489362 (-8625 3425);
PAINT SKYBLUE (-8625 3425);
FORCEPROP 1 LAST VOLTAGE 25V
J 2
(-8625 3375);
DISPLAY 0.489362 (-8625 3375);
PAINT SKYBLUE (-8625 3375);
FORCEPROP 2 LAST CDS_LIB pure_quanta
J 0
(-8575 3375);
DISPLAY INVISIBLE (-8575 3375);
FORCEPROP 1 LAST PATH I4
J 2
(-8625 3525);
DISPLAY 0.978723 (-8625 3525);
PAINT WHITE (-8625 3525);
DISPLAY INVISIBLE (-8625 3525);
FORCEPROP 1 LAST PART_NUMBER CH4104K1B00
J 2
(-8650 3225);
DISPLAY 0.489362 (-8650 3225);
PAINT SKYBLUE (-8650 3225);
DISPLAY INVISIBLE (-8650 3225);
FORCEADD Q_CAP..1
(-2275 3325);
FORCEPROP 1 LAST LOCATION PC288
J 0
(-2225 3425);
DISPLAY 0.489362 (-2225 3425);
PAINT SKYBLUE (-2225 3425);
FORCEPROP 0 LAST $SEC 1
J 0
(-2225 3475);
DISPLAY 0.680851 (-2225 3475);
PAINT MONO (-2225 3475);
DISPLAY INVISIBLE (-2225 3475);
FORCEPROP 0 LAST CDS_SEC 1
J 0
(-2225 3475);
DISPLAY 1.021277 (-2225 3475);
DISPLAY INVISIBLE (-2225 3475);
FORCEPROP 1 LASTPIN (-2275 3425) $PN 1
J 0
(-2265 3405);
DISPLAY 0.489362 (-2265 3405);
PAINT MONO (-2265 3405);
FORCEPROP 1 LASTPIN (-2275 3225) $PN 2
J 0
(-2265 3205);
DISPLAY 0.489362 (-2265 3205);
PAINT MONO (-2265 3205);
FORCEPROP 1 LAST MATERIAL X6S
J 0
(-2225 3225);
DISPLAY 0.489362 (-2225 3225);
PAINT SKYBLUE (-2225 3225);
FORCEPROP 1 LAST TOLERANCE 20%
J 0
(-2225 3275);
DISPLAY 0.489362 (-2225 3275);
PAINT SKYBLUE (-2225 3275);
FORCEPROP 1 LAST VALUE 22UF
J 0
(-2225 3375);
DISPLAY 0.489362 (-2225 3375);
PAINT SKYBLUE (-2225 3375);
FORCEPROP 1 LAST VOLTAGE 4V
J 0
(-2225 3325);
DISPLAY 0.489362 (-2225 3325);
PAINT SKYBLUE (-2225 3325);
FORCEPROP 1 LAST PACK_TYPE C0805
J 0
(-2225 3175);
DISPLAY 0.489362 (-2225 3175);
PAINT SKYBLUE (-2225 3175);
FORCEPROP 2 LAST CDS_LIB pure_quanta
J 0
(-2275 3325);
DISPLAY INVISIBLE (-2275 3325);
FORCEPROP 1 LAST PATH I40
J 0
(-2225 3475);
DISPLAY 0.978723 (-2225 3475);
PAINT WHITE (-2225 3475);
DISPLAY INVISIBLE (-2225 3475);
FORCEPROP 1 LAST PART_NUMBER CH622KMEA03
J 0
(-2225 3175);
DISPLAY 0.489362 (-2225 3175);
PAINT SKYBLUE (-2225 3175);
DISPLAY INVISIBLE (-2225 3175);
FORCEADD Q_CAP..1
(-2025 3325);
FORCEPROP 1 LAST LOCATION PC260
J 0
(-1975 3425);
DISPLAY 0.489362 (-1975 3425);
PAINT SKYBLUE (-1975 3425);
FORCEPROP 0 LAST $SEC 1
J 0
(-1975 3475);
DISPLAY 0.680851 (-1975 3475);
PAINT MONO (-1975 3475);
DISPLAY INVISIBLE (-1975 3475);
FORCEPROP 0 LAST CDS_SEC 1
J 0
(-1975 3475);
DISPLAY 0.680851 (-1975 3475);
DISPLAY INVISIBLE (-1975 3475);
FORCEPROP 1 LASTPIN (-2025 3425) $PN 1
J 0
(-2015 3405);
DISPLAY 0.489362 (-2015 3405);
PAINT MONO (-2015 3405);
FORCEPROP 1 LASTPIN (-2025 3225) $PN 2
J 0
(-2015 3205);
DISPLAY 0.489362 (-2015 3205);
PAINT MONO (-2015 3205);
FORCEPROP 1 LAST VALUE 22UF
J 0
(-1975 3375);
DISPLAY 0.489362 (-1975 3375);
PAINT SKYBLUE (-1975 3375);
FORCEPROP 1 LAST VOLTAGE 4V
J 0
(-1975 3325);
DISPLAY 0.489362 (-1975 3325);
PAINT SKYBLUE (-1975 3325);
FORCEPROP 1 LAST TOLERANCE 20%
J 0
(-1975 3275);
DISPLAY 0.489362 (-1975 3275);
PAINT SKYBLUE (-1975 3275);
FORCEPROP 1 LAST PACK_TYPE C0805
J 0
(-1975 3175);
DISPLAY 0.489362 (-1975 3175);
PAINT SKYBLUE (-1975 3175);
FORCEPROP 1 LAST MATERIAL EMPTY
J 0
(-1975 3225);
DISPLAY 0.489362 (-1975 3225);
PAINT RED (-1975 3225);
FORCEPROP 2 LAST CDS_LIB pure_quanta
J 0
(-2025 3325);
DISPLAY INVISIBLE (-2025 3325);
FORCEPROP 1 LAST PATH I41
J 0
(-1975 3475);
DISPLAY 0.978723 (-1975 3475);
PAINT WHITE (-1975 3475);
DISPLAY INVISIBLE (-1975 3475);
FORCEPROP 1 LAST PART_NUMBER CH622KMEA03
J 0
(-1975 3175);
DISPLAY 0.489362 (-1975 3175);
PAINT SKYBLUE (-1975 3175);
DISPLAY INVISIBLE (-1975 3175);
FORCEADD Q_RES..1
(-1700 2825);
FORCEPROP 1 LAST LOCATION PR438
J 0
(-1725 2875);
DISPLAY 0.489362 (-1725 2875);
PAINT SKYBLUE (-1725 2875);
FORCEPROP 0 LAST $SEC 1
J 0
(-1750 2925);
DISPLAY 0.680851 (-1750 2925);
PAINT MONO (-1750 2925);
DISPLAY INVISIBLE (-1750 2925);
FORCEPROP 0 LAST CDS_SEC 1
J 0
(-1750 2925);
DISPLAY 1.021277 (-1750 2925);
DISPLAY INVISIBLE (-1750 2925);
FORCEPROP 1 LASTPIN (-1800 2825) $PN 1
J 0
(-1788 2837);
DISPLAY 0.489362 (-1788 2837);
PAINT MONO (-1788 2837);
FORCEPROP 1 LASTPIN (-1600 2825) $PN 2
J 0
(-1638 2837);
DISPLAY 0.489362 (-1638 2837);
PAINT MONO (-1638 2837);
FORCEPROP 1 LAST PACK_TYPE 0402LF
J 0
(-1600 2750);
DISPLAY 0.489362 (-1600 2750);
PAINT SKYBLUE (-1600 2750);
FORCEPROP 1 LAST VALUE 49.9
J 2
(-1825 2875);
DISPLAY 0.489362 (-1825 2875);
PAINT SKYBLUE (-1825 2875);
FORCEPROP 1 LAST TOLERANCE 1%
J 0
(-1875 2725);
DISPLAY 0.489362 (-1875 2725);
PAINT SKYBLUE (-1875 2725);
FORCEPROP 1 LAST WATTAGE 1/16W
J 2
(-1450 2850);
DISPLAY 0.489362 (-1450 2850);
PAINT SKYBLUE (-1450 2850);
FORCEPROP 1 LAST MATERIAL CHIP
J 0
(-1575 2775);
DISPLAY 0.489362 (-1575 2775);
PAINT SKYBLUE (-1575 2775);
FORCEPROP 2 LAST CDS_LIB pure_quanta
R 3
J 0
(-1700 2825);
DISPLAY INVISIBLE (-1700 2825);
FORCEPROP 1 LAST PATH I42
J 0
(-1750 2975);
DISPLAY 0.978723 (-1750 2975);
PAINT WHITE (-1750 2975);
DISPLAY INVISIBLE (-1750 2975);
FORCEPROP 1 LAST PART_NUMBER CS04992FB07
J 0
(-2000 2775);
DISPLAY 0.489362 (-2000 2775);
PAINT SKYBLUE (-2000 2775);
DISPLAY INVISIBLE (-2000 2775);
FORCEADD OFFPAGE..1
R 2
(-1400 2025);
FORCEPROP 2 LAST $XR0 27 
J 0
(-1124 2025);
DISPLAY 0.638298 (-1124 2025);
PAINT MONO (-1124 2025);
FORCEPROP 2 LAST CDS_LIB standard
J 0
(-1400 2025);
DISPLAY INVISIBLE (-1400 2025);
FORCEPROP 1 LAST OFFPAGE TRUE
J 2
(-1725 1900);
DISPLAY 0.872340 (-1725 1900);
PAINT GREEN (-1725 1900);
DISPLAY INVISIBLE (-1725 1900);
FORCEPROP 1 LAST COMMENT_BODY TRUE
J 2
(-1525 1925);
DISPLAY 0.872340 (-1525 1925);
PAINT GREEN (-1525 1925);
DISPLAY INVISIBLE (-1525 1925);
FORCEPROP 2 LAST PATH I43
J 0
(-1100 2075);
DISPLAY 0.680851 (-1100 2075);
DISPLAY INVISIBLE (-1100 2075);
FORCEADD OFFPAGE..1
R 2
(-1400 2325);
FORCEPROP 2 LAST $XR0 27 
J 0
(-1124 2325);
DISPLAY 0.638298 (-1124 2325);
PAINT MONO (-1124 2325);
FORCEPROP 2 LAST CDS_LIB standard
J 0
(-1400 2325);
DISPLAY INVISIBLE (-1400 2325);
FORCEPROP 1 LAST OFFPAGE TRUE
J 2
(-1725 2200);
DISPLAY 0.872340 (-1725 2200);
PAINT GREEN (-1725 2200);
DISPLAY INVISIBLE (-1725 2200);
FORCEPROP 1 LAST COMMENT_BODY TRUE
J 2
(-1525 2225);
DISPLAY 0.872340 (-1525 2225);
PAINT GREEN (-1525 2225);
DISPLAY INVISIBLE (-1525 2225);
FORCEPROP 2 LAST PATH I44
J 0
(-1100 2375);
DISPLAY 0.680851 (-1100 2375);
DISPLAY INVISIBLE (-1100 2375);
FORCEADD UNIVERSAL_GND..1
(-1100 2950);
FORCEPROP 3 LASTPIN (-1100 3000) SIG_NAME GND\g
J 0
(-1090 3010);
DISPLAY 0.659574 (-1090 3010);
PAINT MONO (-1090 3010);
DISPLAY INVISIBLE (-1090 3010);
FORCEPROP 2 LAST CDS_LIB pure_quanta_power
J 0
(-1100 2950);
DISPLAY INVISIBLE (-1100 2950);
FORCEPROP 1 LAST HDL_POWER GND
J 1
(-1075 2875);
DISPLAY 0.872340 (-1075 2875);
PAINT GREEN (-1075 2875);
DISPLAY INVISIBLE (-1075 2875);
FORCEPROP 1 LAST PATH I45
J 0
(-1025 2950);
DISPLAY 0.872340 (-1025 2950);
PAINT AQUA (-1025 2950);
DISPLAY INVISIBLE (-1025 2950);
FORCEADD Q_CAP..1
(-1700 3325);
FORCEPROP 1 LAST LOCATION PC261
J 0
(-1650 3425);
DISPLAY 0.489362 (-1650 3425);
PAINT SKYBLUE (-1650 3425);
FORCEPROP 0 LAST $SEC 1
J 0
(-1650 3475);
DISPLAY 0.680851 (-1650 3475);
PAINT MONO (-1650 3475);
DISPLAY INVISIBLE (-1650 3475);
FORCEPROP 0 LAST CDS_SEC 1
J 0
(-1650 3475);
DISPLAY 0.680851 (-1650 3475);
DISPLAY INVISIBLE (-1650 3475);
FORCEPROP 1 LASTPIN (-1700 3425) $PN 1
J 0
(-1690 3405);
DISPLAY 0.489362 (-1690 3405);
PAINT MONO (-1690 3405);
FORCEPROP 1 LASTPIN (-1700 3225) $PN 2
J 0
(-1690 3205);
DISPLAY 0.489362 (-1690 3205);
PAINT MONO (-1690 3205);
FORCEPROP 1 LAST PACK_TYPE C0805
J 0
(-1650 3175);
DISPLAY 0.489362 (-1650 3175);
PAINT SKYBLUE (-1650 3175);
FORCEPROP 1 LAST MATERIAL EMPTY
J 0
(-1650 3225);
DISPLAY 0.489362 (-1650 3225);
PAINT RED (-1650 3225);
FORCEPROP 1 LAST TOLERANCE 20%
J 0
(-1650 3275);
DISPLAY 0.489362 (-1650 3275);
PAINT SKYBLUE (-1650 3275);
FORCEPROP 1 LAST VALUE 22UF
J 0
(-1650 3375);
DISPLAY 0.489362 (-1650 3375);
PAINT SKYBLUE (-1650 3375);
FORCEPROP 1 LAST VOLTAGE 4V
J 0
(-1650 3325);
DISPLAY 0.489362 (-1650 3325);
PAINT SKYBLUE (-1650 3325);
FORCEPROP 2 LAST CDS_LIB pure_quanta
J 0
(-1700 3325);
DISPLAY INVISIBLE (-1700 3325);
FORCEPROP 1 LAST PATH I46
J 0
(-1650 3475);
DISPLAY 0.978723 (-1650 3475);
PAINT WHITE (-1650 3475);
DISPLAY INVISIBLE (-1650 3475);
FORCEPROP 1 LAST PART_NUMBER CH622KMEA03
J 0
(-1650 3175);
DISPLAY 0.489362 (-1650 3175);
PAINT SKYBLUE (-1650 3175);
DISPLAY INVISIBLE (-1650 3175);
FORCEADD Q_CAPP..1
(-1425 3325);
FORCEPROP 1 LAST LOCATION PC115
J 0
(-1375 3425);
DISPLAY 0.489362 (-1375 3425);
PAINT SKYBLUE (-1375 3425);
FORCEPROP 0 LAST $SEC 1
J 0
(-1375 3450);
DISPLAY 0.680851 (-1375 3450);
PAINT MONO (-1375 3450);
DISPLAY INVISIBLE (-1375 3450);
FORCEPROP 0 LAST CDS_SEC 1
J 0
(-1375 3450);
DISPLAY 1.021277 (-1375 3450);
DISPLAY INVISIBLE (-1375 3450);
FORCEPROP 1 LASTPIN (-1425 3425) $PN 1
J 0
(-1415 3410);
DISPLAY 0.489362 (-1415 3410);
PAINT MONO (-1415 3410);
FORCEPROP 1 LASTPIN (-1425 3225) $PN 2
J 0
(-1415 3210);
DISPLAY 0.489362 (-1415 3210);
PAINT MONO (-1415 3210);
FORCEPROP 1 LAST MATERIAL ALUM
J 0
(-1375 3225);
DISPLAY 0.489362 (-1375 3225);
PAINT SKYBLUE (-1375 3225);
FORCEPROP 1 LAST TOLERANCE 20%
J 0
(-1375 3325);
DISPLAY 0.489362 (-1375 3325);
PAINT SKYBLUE (-1375 3325);
FORCEPROP 1 LAST VALUE 390UF
J 0
(-1375 3375);
DISPLAY 0.489362 (-1375 3375);
PAINT SKYBLUE (-1375 3375);
FORCEPROP 1 LAST VOLTAGE 2.5V
J 0
(-1375 3275);
DISPLAY 0.489362 (-1375 3275);
PAINT SKYBLUE (-1375 3275);
FORCEPROP 1 LAST PACK_TYPE SMLF
J 0
(-1375 3175);
DISPLAY 0.489362 (-1375 3175);
PAINT SKYBLUE (-1375 3175);
FORCEPROP 2 LAST CDS_LIB pure_quanta
J 0
(-1425 3325);
DISPLAY INVISIBLE (-1425 3325);
FORCEPROP 1 LAST PATH I47
J 0
(-1375 3475);
DISPLAY 0.978723 (-1375 3475);
DISPLAY INVISIBLE (-1375 3475);
FORCEPROP 1 LAST PART_NUMBER CC7390JMZ13
J 0
(-1375 3125);
DISPLAY 0.489362 (-1375 3125);
PAINT SKYBLUE (-1375 3125);
DISPLAY INVISIBLE (-1375 3125);
FORCEADD Q_CAP..1
(-1100 3325);
FORCEPROP 1 LAST LOCATION PC215
J 0
(-1050 3425);
DISPLAY 0.489362 (-1050 3425);
PAINT SKYBLUE (-1050 3425);
FORCEPROP 2 LAST SEC 1
J 0
(-1048 3532);
DISPLAY 0.680851 (-1048 3532);
PAINT MONO (-1048 3532);
DISPLAY INVISIBLE (-1048 3532);
FORCEPROP 1 LASTPIN (-1100 3425) $PN 1
J 0
(-1090 3405);
DISPLAY 0.489362 (-1090 3405);
FORCEPROP 1 LASTPIN (-1100 3225) $PN 2
J 0
(-1090 3205);
DISPLAY 0.489362 (-1090 3205);
FORCEPROP 1 LAST PACK_TYPE 0402
J 0
(-1050 3125);
DISPLAY 0.489362 (-1050 3125);
PAINT SKYBLUE (-1050 3125);
FORCEPROP 1 LAST VOLTAGE 25V
J 0
(-1050 3325);
DISPLAY 0.489362 (-1050 3325);
PAINT SKYBLUE (-1050 3325);
FORCEPROP 1 LAST VALUE 0.1UF
J 0
(-1050 3375);
DISPLAY 0.489362 (-1050 3375);
PAINT SKYBLUE (-1050 3375);
FORCEPROP 1 LAST TOLERANCE 10%
J 0
(-1050 3275);
DISPLAY 0.489362 (-1050 3275);
PAINT SKYBLUE (-1050 3275);
FORCEPROP 1 LAST MATERIAL X7R
J 0
(-1050 3225);
DISPLAY 0.489362 (-1050 3225);
PAINT SKYBLUE (-1050 3225);
FORCEPROP 2 LAST SEC_TYPE 0402
J 0
(-1050 3521);
DISPLAY 1.021277 (-1050 3521);
DISPLAY INVISIBLE (-1050 3521);
FORCEPROP 2 LAST CDS_LIB pure_quanta
J 0
(-1100 3325);
PAINT MONO (-1100 3325);
DISPLAY INVISIBLE (-1100 3325);
FORCEPROP 1 LAST PATH I48
J 0
(-1050 3475);
DISPLAY 0.978723 (-1050 3475);
PAINT WHITE (-1050 3475);
DISPLAY INVISIBLE (-1050 3475);
FORCEPROP 1 LAST PART_NUMBER CH4104K1B00
J 0
(-1050 3175);
DISPLAY 0.489362 (-1050 3175);
PAINT SKYBLUE (-1050 3175);
DISPLAY INVISIBLE (-1050 3175);
FORCEADD UNIVERSAL_GND..1
(-500 2775);
FORCEPROP 3 LASTPIN (-500 2825) SIG_NAME GND\g
J 0
(-490 2835);
DISPLAY 0.659574 (-490 2835);
PAINT MONO (-490 2835);
DISPLAY INVISIBLE (-490 2835);
FORCEPROP 2 LAST CDS_LIB pure_quanta_power
J 0
(-500 2775);
DISPLAY INVISIBLE (-500 2775);
FORCEPROP 1 LAST HDL_POWER GND
J 1
(-475 2700);
DISPLAY 0.872340 (-475 2700);
PAINT GREEN (-475 2700);
DISPLAY INVISIBLE (-475 2700);
FORCEPROP 1 LAST PATH I49
J 0
(-425 2775);
DISPLAY 0.872340 (-425 2775);
PAINT AQUA (-425 2775);
DISPLAY INVISIBLE (-425 2775);
FORCEADD Q_CAP..1
(-9225 4150);
FORCEPROP 1 LAST LOCATION PC6001
J 0
(-9175 4250);
DISPLAY 0.489362 (-9175 4250);
PAINT SKYBLUE (-9175 4250);
FORCEPROP 0 LAST $SEC 1
J 0
(-9175 4275);
DISPLAY 0.680851 (-9175 4275);
PAINT MONO (-9175 4275);
DISPLAY INVISIBLE (-9175 4275);
FORCEPROP 0 LAST CDS_SEC 1
J 0
(-9175 4275);
DISPLAY 0.680851 (-9175 4275);
DISPLAY INVISIBLE (-9175 4275);
FORCEPROP 1 LASTPIN (-9225 4250) $PN 1
J 0
(-9215 4230);
DISPLAY 0.787234 (-9215 4230);
PAINT MONO (-9215 4230);
FORCEPROP 1 LASTPIN (-9225 4050) $PN 2
J 0
(-9215 4030);
DISPLAY 0.787234 (-9215 4030);
PAINT MONO (-9215 4030);
FORCEPROP 1 LAST PACK_TYPE C0402
J 0
(-9175 3950);
DISPLAY 0.489362 (-9175 3950);
PAINT SKYBLUE (-9175 3950);
FORCEPROP 1 LAST TOLERANCE 10%
J 0
(-9175 4100);
DISPLAY 0.489362 (-9175 4100);
PAINT SKYBLUE (-9175 4100);
FORCEPROP 1 LAST VALUE 0.1UF
J 0
(-9175 4200);
DISPLAY 0.489362 (-9175 4200);
PAINT SKYBLUE (-9175 4200);
FORCEPROP 1 LAST VOLTAGE 25V
J 0
(-9175 4150);
DISPLAY 0.489362 (-9175 4150);
PAINT SKYBLUE (-9175 4150);
FORCEPROP 1 LAST MATERIAL X6S
J 0
(-9175 4050);
DISPLAY 0.489362 (-9175 4050);
PAINT SKYBLUE (-9175 4050);
FORCEPROP 2 LAST CDS_LIB pure_quanta
J 0
(-9225 4150);
DISPLAY INVISIBLE (-9225 4150);
FORCEPROP 1 LAST PATH I5
J 0
(-9175 4300);
DISPLAY 0.978723 (-9175 4300);
PAINT WHITE (-9175 4300);
DISPLAY INVISIBLE (-9175 4300);
FORCEPROP 1 LAST PART_NUMBER CH4104KEB00
J 0
(-9175 4000);
DISPLAY 0.489362 (-9175 4000);
PAINT SKYBLUE (-9175 4000);
DISPLAY INVISIBLE (-9175 4000);
FORCEADD P1V0..1
(-500 3950);
FORCEPROP 3 LASTPIN (-500 3900) SIG_NAME PVDD18_S5_P0\g
J 0
(-490 3910);
DISPLAY 0.659574 (-490 3910);
PAINT MONO (-490 3910);
DISPLAY INVISIBLE (-490 3910);
FORCEPROP 1 LAST HDL_POWER PVDD18_S5_P0
J 1
(-500 4000);
DISPLAY 0.489362 (-500 4000);
PAINT GREEN (-500 4000);
FORCEPROP 2 LAST CDS_LIB pure_quanta_power
J 0
(-500 3950);
PAINT MONO (-500 3950);
DISPLAY INVISIBLE (-500 3950);
FORCEPROP 1 LAST PATH I50
J 0
(-450 3975);
DISPLAY 0.872340 (-450 3975);
PAINT AQUA (-450 3975);
DISPLAY INVISIBLE (-450 3975);
FORCEADD Q_RES..2
(-500 3300);
FORCEPROP 1 LAST LOCATION PR439
J 0
(-455 3425);
DISPLAY 0.489362 (-455 3425);
PAINT SKYBLUE (-455 3425);
FORCEPROP 0 LAST $SEC 1
J 0
(-450 3450);
DISPLAY 0.680851 (-450 3450);
PAINT MONO (-450 3450);
DISPLAY INVISIBLE (-450 3450);
FORCEPROP 0 LAST CDS_SEC 1
J 0
(-450 3450);
DISPLAY 1.021277 (-450 3450);
DISPLAY INVISIBLE (-450 3450);
FORCEPROP 1 LASTPIN (-500 3400) $PN 1
J 0
(-495 3362);
DISPLAY 0.489362 (-495 3362);
PAINT MONO (-495 3362);
FORCEPROP 1 LASTPIN (-500 3200) $PN 2
J 0
(-495 3210);
DISPLAY 0.489362 (-495 3210);
PAINT MONO (-495 3210);
FORCEPROP 1 LAST WATTAGE 1/16W
J 0
(-460 3275);
DISPLAY 0.489362 (-460 3275);
PAINT SKYBLUE (-460 3275);
FORCEPROP 1 LAST MATERIAL CHIP
J 0
(-460 3225);
DISPLAY 0.489362 (-460 3225);
PAINT SKYBLUE (-460 3225);
FORCEPROP 1 LAST TOLERANCE 1%
J 0
(-455 3325);
DISPLAY 0.489362 (-455 3325);
PAINT SKYBLUE (-455 3325);
FORCEPROP 1 LAST VALUE 1K
J 0
(-455 3375);
DISPLAY 0.489362 (-455 3375);
PAINT SKYBLUE (-455 3375);
FORCEPROP 1 LAST PACK_TYPE 0402LF
J 0
(-460 3125);
DISPLAY 0.489362 (-460 3125);
PAINT SKYBLUE (-460 3125);
FORCEPROP 2 LAST CDS_LIB pure_quanta
J 0
(-500 3300);
DISPLAY INVISIBLE (-500 3300);
FORCEPROP 1 LAST PATH I51
J 0
(-450 3475);
DISPLAY 0.978723 (-450 3475);
PAINT WHITE (-450 3475);
DISPLAY INVISIBLE (-450 3475);
FORCEPROP 1 LAST PART_NUMBER CS21002FB06
J 0
(-460 3175);
DISPLAY 0.489362 (-460 3175);
PAINT SKYBLUE (-460 3175);
DISPLAY INVISIBLE (-460 3175);
FORCEADD Q_RES..1
(-3650 4075);
FORCEPROP 1 LAST LOCATION R177
J 0
(-3525 4075);
DISPLAY 0.489362 (-3525 4075);
PAINT SKYBLUE (-3525 4075);
FORCEPROP 0 LAST $SEC 1
J 2
(-3525 4125);
DISPLAY 0.680851 (-3525 4125);
PAINT MONO (-3525 4125);
DISPLAY INVISIBLE (-3525 4125);
FORCEPROP 0 LAST CDS_SEC 1
J 2
(-3525 4125);
DISPLAY 1.021277 (-3525 4125);
DISPLAY INVISIBLE (-3525 4125);
FORCEPROP 1 LASTPIN (-3750 4075) $PN 1
J 0
(-3738 4087);
DISPLAY 0.489362 (-3738 4087);
PAINT MONO (-3738 4087);
FORCEPROP 1 LASTPIN (-3550 4075) $PN 2
J 0
(-3588 4087);
DISPLAY 0.489362 (-3588 4087);
PAINT MONO (-3588 4087);
FORCEPROP 1 LAST VALUE 33
J 2
(-3775 4075);
DISPLAY 0.489362 (-3775 4075);
PAINT SKYBLUE (-3775 4075);
FORCEPROP 1 LAST PACK_TYPE 0402LF
J 2
(-3475 4000);
DISPLAY 0.489362 (-3475 4000);
PAINT SKYBLUE (-3475 4000);
DISPLAY INVISIBLE (-3475 4000);
FORCEPROP 1 LAST TOLERANCE 5%
J 0
(-3775 4050);
DISPLAY 0.489362 (-3775 4050);
PAINT SKYBLUE (-3775 4050);
DISPLAY INVISIBLE (-3775 4050);
FORCEPROP 1 LAST MATERIAL CHIP
J 2
(-3475 4050);
DISPLAY 0.489362 (-3475 4050);
PAINT SKYBLUE (-3475 4050);
DISPLAY INVISIBLE (-3475 4050);
FORCEPROP 1 LAST WATTAGE 1/16W
J 2
(-3725 4000);
DISPLAY 0.489362 (-3725 4000);
PAINT SKYBLUE (-3725 4000);
DISPLAY INVISIBLE (-3725 4000);
FORCEPROP 2 LAST BOM_COST MEM
J 2
(-3625 4225);
DISPLAY 0.744681 (-3625 4225);
PAINT WHITE (-3625 4225);
DISPLAY INVISIBLE (-3625 4225);
FORCEPROP 2 LAST CDS_LIB pure_quanta
J 2
(-3650 4075);
DISPLAY INVISIBLE (-3650 4075);
FORCEPROP 1 LAST PATH I52
J 0
(-3700 4225);
DISPLAY 0.978723 (-3700 4225);
PAINT WHITE (-3700 4225);
DISPLAY INVISIBLE (-3700 4225);
FORCEPROP 1 LAST PART_NUMBER CS03302JB10
J 2
(-3550 4125);
DISPLAY 0.489362 (-3550 4125);
PAINT SKYBLUE (-3550 4125);
DISPLAY INVISIBLE (-3550 4125);
FORCEADD OFFPAGE..2
(-2600 4075);
FORCEPROP 2 LAST $XR0 81 
J 0
(-2411 4075);
DISPLAY 0.638298 (-2411 4075);
PAINT MONO (-2411 4075);
FORCEPROP 2 LAST ROOM VR_CORE0_CTRL
J 2
(-2325 4125);
PAINT RED (-2325 4125);
DISPLAY INVISIBLE (-2325 4125);
FORCEPROP 2 LAST CDS_LIB standard
J 0
(-2600 4075);
DISPLAY INVISIBLE (-2600 4075);
FORCEPROP 1 LAST OFFPAGE TRUE
J 0
(-2275 3950);
DISPLAY 1.170213 (-2275 3950);
PAINT GREEN (-2275 3950);
DISPLAY INVISIBLE (-2275 3950);
FORCEPROP 1 LAST COMMENT_BODY TRUE
J 0
(-2645 3980);
DISPLAY 1.170213 (-2645 3980);
PAINT GREEN (-2645 3980);
DISPLAY INVISIBLE (-2645 3980);
FORCEPROP 2 LAST PATH I53
J 0
(-2400 4125);
DISPLAY 0.680851 (-2400 4125);
DISPLAY INVISIBLE (-2400 4125);
FORCEADD Q_CAP..1
(-2475 3325);
FORCEPROP 1 LAST LOCATION PC285
J 0
(-2425 3425);
DISPLAY 0.489362 (-2425 3425);
PAINT SKYBLUE (-2425 3425);
FORCEPROP 0 LAST $SEC 1
J 0
(-2425 3475);
DISPLAY 0.680851 (-2425 3475);
PAINT MONO (-2425 3475);
DISPLAY INVISIBLE (-2425 3475);
FORCEPROP 0 LAST CDS_SEC 1
J 0
(-2425 3475);
DISPLAY 1.021277 (-2425 3475);
DISPLAY INVISIBLE (-2425 3475);
FORCEPROP 1 LASTPIN (-2475 3425) $PN 1
J 0
(-2465 3405);
DISPLAY 0.489362 (-2465 3405);
PAINT MONO (-2465 3405);
FORCEPROP 1 LASTPIN (-2475 3225) $PN 2
J 0
(-2465 3205);
DISPLAY 0.489362 (-2465 3205);
PAINT MONO (-2465 3205);
FORCEPROP 1 LAST MATERIAL X6S
J 0
(-2425 3225);
DISPLAY 0.489362 (-2425 3225);
PAINT SKYBLUE (-2425 3225);
FORCEPROP 1 LAST VOLTAGE 4V
J 0
(-2425 3325);
DISPLAY 0.489362 (-2425 3325);
PAINT SKYBLUE (-2425 3325);
FORCEPROP 1 LAST TOLERANCE 20%
J 0
(-2425 3275);
DISPLAY 0.489362 (-2425 3275);
PAINT SKYBLUE (-2425 3275);
FORCEPROP 1 LAST PACK_TYPE C0805
J 0
(-2425 3175);
DISPLAY 0.489362 (-2425 3175);
PAINT SKYBLUE (-2425 3175);
FORCEPROP 1 LAST VALUE 22UF
J 0
(-2425 3375);
DISPLAY 0.489362 (-2425 3375);
PAINT SKYBLUE (-2425 3375);
FORCEPROP 2 LAST CDS_LIB pure_quanta
J 0
(-2475 3325);
DISPLAY INVISIBLE (-2475 3325);
FORCEPROP 1 LAST PATH I54
J 0
(-2425 3475);
DISPLAY 0.978723 (-2425 3475);
PAINT WHITE (-2425 3475);
DISPLAY INVISIBLE (-2425 3475);
FORCEPROP 1 LAST PART_NUMBER CH622KMEA03
J 0
(-2425 3175);
DISPLAY 0.489362 (-2425 3175);
PAINT SKYBLUE (-2425 3175);
DISPLAY INVISIBLE (-2425 3175);
FORCEADD UNIVERSAL_GND..1
(-2850 3725);
FORCEPROP 3 LASTPIN (-2850 3775) SIG_NAME GND\g
J 0
(-2840 3785);
DISPLAY 0.659574 (-2840 3785);
PAINT MONO (-2840 3785);
DISPLAY INVISIBLE (-2840 3785);
FORCEPROP 2 LAST CDS_LIB pure_quanta_power
J 0
(-2850 3725);
DISPLAY INVISIBLE (-2850 3725);
FORCEPROP 1 LAST HDL_POWER GND
J 1
(-2825 3650);
DISPLAY 0.872340 (-2825 3650);
PAINT GREEN (-2825 3650);
DISPLAY INVISIBLE (-2825 3650);
FORCEPROP 1 LAST PATH I55
J 0
(-2775 3725);
DISPLAY 0.872340 (-2775 3725);
PAINT AQUA (-2775 3725);
DISPLAY INVISIBLE (-2775 3725);
FORCEADD Q_CAP..1
(-2850 3925);
FORCEPROP 1 LAST LOCATION C5001
J 0
(-2800 4025);
DISPLAY 0.638298 (-2800 4025);
FORCEPROP 0 LAST $SEC 1
J 0
(-2800 4075);
DISPLAY 0.680851 (-2800 4075);
PAINT MONO (-2800 4075);
DISPLAY INVISIBLE (-2800 4075);
FORCEPROP 0 LAST CDS_SEC 1
J 0
(-2800 4075);
DISPLAY 0.680851 (-2800 4075);
DISPLAY INVISIBLE (-2800 4075);
FORCEPROP 1 LASTPIN (-2850 4025) $PN 1
J 0
(-2840 4005);
DISPLAY 0.787234 (-2840 4005);
PAINT MONO (-2840 4005);
FORCEPROP 1 LASTPIN (-2850 3825) $PN 2
J 0
(-2840 3805);
DISPLAY 0.787234 (-2840 3805);
PAINT MONO (-2840 3805);
FORCEPROP 1 LAST PACK_TYPE 0402
J 0
(-2800 3725);
DISPLAY 0.638298 (-2800 3725);
FORCEPROP 1 LAST VALUE 1000PF
J 0
(-2800 3975);
DISPLAY 0.638298 (-2800 3975);
FORCEPROP 1 LAST VOLTAGE 50V
J 0
(-2800 3925);
DISPLAY 0.638298 (-2800 3925);
FORCEPROP 1 LAST MATERIAL X7R
J 0
(-2800 3825);
DISPLAY 0.638298 (-2800 3825);
FORCEPROP 1 LAST TOLERANCE 5%
J 0
(-2800 3875);
DISPLAY 0.638298 (-2800 3875);
FORCEPROP 2 LAST CDS_LIB pure_quanta
J 0
(-2850 3925);
DISPLAY INVISIBLE (-2850 3925);
FORCEPROP 1 LAST PATH I56
J 0
(-2800 4075);
DISPLAY 0.978723 (-2800 4075);
PAINT WHITE (-2800 4075);
DISPLAY INVISIBLE (-2800 4075);
FORCEPROP 1 LAST PART_NUMBER TMP_QCH21006JB10
J 0
(-2800 3775);
DISPLAY 0.638298 (-2800 3775);
DISPLAY INVISIBLE (-2800 3775);
FORCEADD Q_CAP..1
(-8200 4125);
FORCEPROP 1 LAST LOCATION PC8002
J 0
(-8150 4225);
DISPLAY 0.489362 (-8150 4225);
PAINT SKYBLUE (-8150 4225);
FORCEPROP 0 LAST $SEC 1
J 0
(-8150 4250);
DISPLAY 0.680851 (-8150 4250);
PAINT MONO (-8150 4250);
DISPLAY INVISIBLE (-8150 4250);
FORCEPROP 0 LAST CDS_SEC 1
J 0
(-8150 4250);
DISPLAY 0.680851 (-8150 4250);
DISPLAY INVISIBLE (-8150 4250);
FORCEPROP 1 LASTPIN (-8200 4225) $PN 1
J 0
(-8190 4205);
DISPLAY 0.787234 (-8190 4205);
PAINT MONO (-8190 4205);
FORCEPROP 1 LASTPIN (-8200 4025) $PN 2
J 0
(-8190 4005);
DISPLAY 0.787234 (-8190 4005);
PAINT MONO (-8190 4005);
FORCEPROP 1 LAST VALUE 22UF
J 0
(-8150 4175);
DISPLAY 0.489362 (-8150 4175);
PAINT SKYBLUE (-8150 4175);
FORCEPROP 1 LAST MATERIAL X6S
J 0
(-8150 4025);
DISPLAY 0.489362 (-8150 4025);
PAINT SKYBLUE (-8150 4025);
FORCEPROP 1 LAST VOLTAGE 16V
J 0
(-8150 4125);
DISPLAY 0.489362 (-8150 4125);
PAINT SKYBLUE (-8150 4125);
FORCEPROP 1 LAST TOLERANCE 20%
J 0
(-8150 4075);
DISPLAY 0.489362 (-8150 4075);
PAINT SKYBLUE (-8150 4075);
FORCEPROP 1 LAST PACK_TYPE C0805
J 0
(-8150 3925);
DISPLAY 0.489362 (-8150 3925);
PAINT SKYBLUE (-8150 3925);
FORCEPROP 2 LAST CDS_LIB pure_quanta
J 0
(-8200 4125);
DISPLAY INVISIBLE (-8200 4125);
FORCEPROP 1 LAST PATH I57
J 0
(-8150 4275);
DISPLAY 0.978723 (-8150 4275);
PAINT WHITE (-8150 4275);
DISPLAY INVISIBLE (-8150 4275);
FORCEPROP 1 LAST PART_NUMBER CH6223MEA01
J 0
(-8150 3975);
DISPLAY 0.489362 (-8150 3975);
PAINT SKYBLUE (-8150 3975);
DISPLAY INVISIBLE (-8150 3975);
FORCEADD Q_RES..1
(-4550 3875);
FORCEPROP 1 LAST LOCATION PR8001
J 0
(-4750 3875);
DISPLAY 0.510638 (-4750 3875);
FORCEPROP 2 LAST SEC 1
J 0
(-4600 4075);
DISPLAY 0.680851 (-4600 4075);
PAINT MONO (-4600 4075);
DISPLAY INVISIBLE (-4600 4075);
FORCEPROP 1 LASTPIN (-4650 3875) $PN 1
J 0
(-4638 3887);
DISPLAY 0.787234 (-4638 3887);
PAINT MONO (-4638 3887);
FORCEPROP 1 LASTPIN (-4450 3875) $PN 2
J 0
(-4488 3887);
DISPLAY 0.787234 (-4488 3887);
PAINT MONO (-4488 3887);
FORCEPROP 1 LAST PACK_TYPE 0402LF
J 0
(-4700 3925);
DISPLAY 0.510638 (-4700 3925);
FORCEPROP 1 LAST TOLERANCE 1%
J 0
(-4475 3825);
DISPLAY 0.638298 (-4475 3825);
FORCEPROP 1 LAST MATERIAL CHIP
J 0
(-4525 3925);
DISPLAY 0.510638 (-4525 3925);
FORCEPROP 1 LAST VALUE 2.2
J 2
(-4600 3825);
DISPLAY 0.638298 (-4600 3825);
FORCEPROP 2 LAST SEC_TYPE 0402LF
J 0
(-4600 4075);
DISPLAY 0.680851 (-4600 4075);
DISPLAY INVISIBLE (-4600 4075);
FORCEPROP 2 LAST CDS_LIB pure_quanta
J 0
(-4550 3875);
DISPLAY INVISIBLE (-4550 3875);
FORCEPROP 1 LAST WATTAGE 1/16W
J 2
(-4300 3950);
DISPLAY 0.510638 (-4300 3950);
DISPLAY INVISIBLE (-4300 3950);
FORCEPROP 1 LAST PATH I58
J 0
(-4600 4025);
DISPLAY 0.978723 (-4600 4025);
PAINT WHITE (-4600 4025);
DISPLAY INVISIBLE (-4600 4025);
FORCEPROP 1 LAST PART_NUMBER CS-2202FB01
J 0
(-4700 3950);
DISPLAY 0.510638 (-4700 3950);
DISPLAY INVISIBLE (-4700 3950);
FORCEADD P1V0_AUX..1
(-9225 4550);
FORCEPROP 3 LASTPIN (-9225 4500) SIG_NAME P12V_AUX\g
J 0
(-9215 4510);
DISPLAY 0.659574 (-9215 4510);
PAINT MONO (-9215 4510);
DISPLAY INVISIBLE (-9215 4510);
FORCEPROP 1 LAST HDL_POWER P12V_AUX
J 1
(-9214 4597);
DISPLAY 0.489362 (-9214 4597);
PAINT GREEN (-9214 4597);
FORCEPROP 2 LAST CDS_LIB mstr_symbols
J 0
(-9225 4550);
DISPLAY INVISIBLE (-9225 4550);
FORCEPROP 1 LAST VOLTAGE 1.0V
J 0
(-9270 4507);
DISPLAY 0.340426 (-9270 4507);
PAINT SKYBLUE (-9270 4507);
DISPLAY INVISIBLE (-9270 4507);
FORCEPROP 2 LAST ROOM VR_DDR1_POWER_STAGE
J 0
(-9225 4650);
DISPLAY 0.978723 (-9225 4650);
PAINT RED (-9225 4650);
DISPLAY INVISIBLE (-9225 4650);
FORCEPROP 1 LAST BODY_TYPE PLUMBING
J 0
(-9270 4507);
DISPLAY 0.340426 (-9270 4507);
PAINT GREEN (-9270 4507);
DISPLAY INVISIBLE (-9270 4507);
FORCEPROP 1 LAST PATH I6
J 0
(-9175 4575);
DISPLAY 0.872340 (-9175 4575);
PAINT AQUA (-9175 4575);
DISPLAY INVISIBLE (-9175 4575);
FORCEADD Q_INDUCTOR..1
(-8875 4375);
FORCEPROP 1 LAST LOCATION PL77
J 0
(-9000 4535);
DISPLAY 0.489362 (-9000 4535);
PAINT SKYBLUE (-9000 4535);
FORCEPROP 0 LAST $SEC 1
J 0
(-9000 4675);
DISPLAY 0.680851 (-9000 4675);
PAINT MONO (-9000 4675);
DISPLAY INVISIBLE (-9000 4675);
FORCEPROP 0 LAST CDS_SEC 1
J 0
(-9000 4675);
DISPLAY 0.680851 (-9000 4675);
DISPLAY INVISIBLE (-9000 4675);
FORCEPROP 0 LASTPIN (-8975 4350) $PN 1
J 2
(-8985 4360);
DISPLAY 0.489362 (-8985 4360);
PAINT MONO (-8985 4360);
FORCEPROP 0 LASTPIN (-8775 4350) $PN 2
J 0
(-8765 4360);
DISPLAY 0.489362 (-8765 4360);
PAINT MONO (-8765 4360);
FORCEPROP 2 LAST VALUE BLM18SN220TN1D/8000MA
J 0
(-9000 4575);
DISPLAY 0.489362 (-9000 4575);
PAINT SKYBLUE (-9000 4575);
FORCEPROP 2 LAST PACK_TYPE SMLF
J 0
(-9000 4625);
DISPLAY 0.489362 (-9000 4625);
PAINT SKYBLUE (-9000 4625);
FORCEPROP 1 LAST MATERIAL IND
J 0
(-9000 4430);
DISPLAY 0.489362 (-9000 4430);
PAINT SKYBLUE (-9000 4430);
FORCEPROP 1 LAST NEEDS_NO_SIZE TRUE
J 0
(-8875 4375);
DISPLAY 0.468085 (-8875 4375);
PAINT GREEN (-8875 4375);
DISPLAY INVISIBLE (-8875 4375);
FORCEPROP 2 LAST CDS_LIB pure_quanta
J 0
(-8875 4375);
DISPLAY INVISIBLE (-8875 4375);
FORCEPROP 1 LAST PATH I7
J 0
(-8800 4430);
DISPLAY 0.723404 (-8800 4430);
PAINT GREEN (-8800 4430);
DISPLAY INVISIBLE (-8800 4430);
FORCEPROP 1 LAST PART_NUMBER CX220TN1001
J 0
(-9000 4485);
DISPLAY 0.489362 (-9000 4485);
PAINT SKYBLUE (-9000 4485);
DISPLAY INVISIBLE (-9000 4485);
FORCEADD Q_CAP..1
(-7875 4125);
FORCEPROP 1 LAST LOCATION PC111
J 0
(-7825 4225);
DISPLAY 0.489362 (-7825 4225);
PAINT SKYBLUE (-7825 4225);
FORCEPROP 0 LAST $SEC 1
J 0
(-7825 4250);
DISPLAY 0.680851 (-7825 4250);
PAINT MONO (-7825 4250);
DISPLAY INVISIBLE (-7825 4250);
FORCEPROP 0 LAST CDS_SEC 1
J 0
(-7825 4250);
DISPLAY 1.021277 (-7825 4250);
DISPLAY INVISIBLE (-7825 4250);
FORCEPROP 1 LASTPIN (-7875 4225) $PN 1
J 0
(-7865 4205);
DISPLAY 0.489362 (-7865 4205);
PAINT MONO (-7865 4205);
FORCEPROP 1 LASTPIN (-7875 4025) $PN 2
J 0
(-7865 4005);
DISPLAY 0.489362 (-7865 4005);
PAINT MONO (-7865 4005);
FORCEPROP 1 LAST VALUE 22UF
J 0
(-7825 4175);
DISPLAY 0.489362 (-7825 4175);
PAINT SKYBLUE (-7825 4175);
FORCEPROP 1 LAST PACK_TYPE C0805
J 0
(-7825 3925);
DISPLAY 0.489362 (-7825 3925);
PAINT SKYBLUE (-7825 3925);
FORCEPROP 1 LAST MATERIAL X6S
J 0
(-7825 4025);
DISPLAY 0.489362 (-7825 4025);
PAINT SKYBLUE (-7825 4025);
FORCEPROP 1 LAST VOLTAGE 16V
J 0
(-7825 4125);
DISPLAY 0.489362 (-7825 4125);
PAINT SKYBLUE (-7825 4125);
FORCEPROP 1 LAST TOLERANCE 20%
J 0
(-7825 4075);
DISPLAY 0.489362 (-7825 4075);
PAINT SKYBLUE (-7825 4075);
FORCEPROP 2 LAST CDS_LIB pure_quanta
J 0
(-7875 4125);
DISPLAY INVISIBLE (-7875 4125);
FORCEPROP 1 LAST PATH I8
J 0
(-7825 4275);
DISPLAY 0.978723 (-7825 4275);
PAINT WHITE (-7825 4275);
DISPLAY INVISIBLE (-7825 4275);
FORCEPROP 1 LAST PART_NUMBER CH6223MEA01
J 0
(-7825 3975);
DISPLAY 0.489362 (-7825 3975);
PAINT SKYBLUE (-7825 3975);
DISPLAY INVISIBLE (-7825 3975);
FORCEADD UNIVERSAL_GND..1
(-8050 2925);
FORCEPROP 3 LASTPIN (-8050 2975) SIG_NAME GND\g
J 0
(-8040 2985);
DISPLAY 0.659574 (-8040 2985);
PAINT MONO (-8040 2985);
DISPLAY INVISIBLE (-8040 2985);
FORCEPROP 2 LAST CDS_LIB pure_quanta_power
J 0
(-8050 2925);
DISPLAY INVISIBLE (-8050 2925);
FORCEPROP 1 LAST HDL_POWER GND
J 1
(-8025 2850);
DISPLAY 0.872340 (-8025 2850);
PAINT GREEN (-8025 2850);
DISPLAY INVISIBLE (-8025 2850);
FORCEPROP 1 LAST PATH I9
J 0
(-7975 2925);
DISPLAY 0.872340 (-7975 2925);
PAINT AQUA (-7975 2925);
DISPLAY INVISIBLE (-7975 2925);
FORCEADD DNS..1
(-8600 3275);
PAINT RED (-8600 3275);
FORCEPROP 2 LAST CDS_LIB mstr_misc
J 0
(-8600 3275);
DISPLAY INVISIBLE (-8600 3275);
FORCEPROP 1 LAST COMMENT_BODY TRUE
J 0
(-8600 3275);
DISPLAY INVISIBLE (-8600 3275);
FORCEADD DNS..1
(-1975 3325);
PAINT RED (-1975 3325);
FORCEPROP 2 LAST CDS_LIB mstr_misc
J 0
(-1975 3325);
DISPLAY INVISIBLE (-1975 3325);
FORCEPROP 1 LAST COMMENT_BODY TRUE
R 1
J 0
(-1900 3100);
DISPLAY 0.872340 (-1900 3100);
PAINT GREEN (-1900 3100);
DISPLAY INVISIBLE (-1900 3100);
FORCEADD DNS..1
(-3150 2150);
PAINT RED (-3150 2150);
FORCEPROP 2 LAST CDS_LIB mstr_misc
J 0
(-3150 2150);
DISPLAY INVISIBLE (-3150 2150);
FORCEPROP 1 LAST COMMENT_BODY TRUE
R 1
J 0
(-3075 1925);
DISPLAY 0.872340 (-3075 1925);
PAINT GREEN (-3075 1925);
DISPLAY INVISIBLE (-3075 1925);
FORCEADD DNS..1
(-1675 3325);
PAINT RED (-1675 3325);
FORCEPROP 2 LAST CDS_LIB mstr_misc
J 0
(-1675 3325);
DISPLAY INVISIBLE (-1675 3325);
FORCEPROP 1 LAST COMMENT_BODY TRUE
R 1
J 0
(-1600 3100);
DISPLAY 0.872340 (-1600 3100);
PAINT GREEN (-1600 3100);
DISPLAY INVISIBLE (-1600 3100);
FORCEADD QUANTA_TITLE_BLOCK_C..1
(0 0);
FORCEPROP 0 LAST CDS_CON_LAST_MODIFIED Thu Sep 14 16:12:41 2023
J 0
(-1885 15);
DISPLAY INVISIBLE (-1885 15);
FORCEPROP 1 LAST CUSTOM_TXT_CDS <CON_LAST_MODIFIED>
J 0
(-1885 15);
DISPLAY 0.978723 (-1885 15);
FORCEPROP 2 LAST CUSTOM_TXT_CDS <XR_PAGE_TITLE>
J 0
(-7890 5250);
DISPLAY 0.638298 (-7890 5250);
PAINT PINK (-7890 5250);
DISPLAY INVISIBLE (-7890 5250);
FORCEPROP 1 LAST CUSTOM_TXT_CDS <NAME_2>
J 0
(-3175 50);
FORCEPROP 1 LAST CUSTOM_TXT_CDS <NAME_1>
J 0
(-3175 175);
FORCEPROP 1 LAST CUSTOM_TXT_CDS <Q_NUMBER>
J 0
(-1403 103);
DISPLAY 1.212766 (-1403 103);
FORCEPROP 1 LAST CUSTOM_TXT_CDS <Q_PROJ>
J 0
(-2382 102);
DISPLAY 1.212766 (-2382 102);
FORCEPROP 1 LAST CUSTOM_TXT_CDS <Q_REV>
J 0
(-184 103);
DISPLAY 1.212766 (-184 103);
FORCEPROP 1 LAST CUSTOM_TXT_CDS <CON_PAGE_NUM> OF <CON_TOTAL_PAGES>
J 0
(-446 18);
DISPLAY 0.978723 (-446 18);
FORCEPROP 1 LAST Q_TITLE PVDD18_S5_P0
J 0
(-9300 50);
DISPLAY 2.446809 (-9300 50);
PAINT GREEN (-9300 50);
FORCEPROP 1 LAST CDS_LMAN_SYM_OUTLINE -9475,6775,100,-125
J 0
(0 0);
DISPLAY 0.468085 (0 0);
PAINT GREEN (0 0);
DISPLAY INVISIBLE (0 0);
FORCEPROP 2 LAST CDS_LIB pure_quanta
J 0
(0 0);
DISPLAY INVISIBLE (0 0);
FORCEPROP 2 LAST PAGE_BORDER TRUE
J 0
(-7890 5250);
DISPLAY 0.638298 (-7890 5250);
PAINT PINK (-7890 5250);
DISPLAY INVISIBLE (-7890 5250);
FORCEPROP 2 LAST CDS_XR_PAGE_TITLE CR-209 : @T6G_MB_LIB.T6G(SCH_1):PAGE209
J 0
(-7890 5250);
DISPLAY 0.638298 (-7890 5250);
PAINT PINK (-7890 5250);
DISPLAY INVISIBLE (-7890 5250);
FORCEPROP 1 LAST Q_DEPT BU9
J 1
(-3763 49);
DISPLAY 1.957447 (-3763 49);
PAINT GREEN (-3763 49);
DISPLAY INVISIBLE (-3763 49);
FORCEPROP 1 LAST COMMENT_BODY TRUE
J 0
(12 -13);
DISPLAY 0.978723 (12 -13);
PAINT GREEN (12 -13);
DISPLAY INVISIBLE (12 -13);
WIRE 16 -1 (-9225 4050)(-9225 3875);
WIRE 16 -1 (-7575 2375)(-7575 2450);
WIRE 16 -1 (-7575 3125)(-7575 3075);
WIRE 16 -1 (-6700 2450)(-6700 2350);
WIRE 16 -1 (-5000 2500)(-5000 2600);
WIRE 16 -1 (-8575 3225)(-8575 3275);
WIRE 16 -1 (-4700 4600)(-4700 4475);
WIRE 16 -1 (-3575 1675)(-3575 1575);
WIRE 16 -1 (-500 2825)(-500 3200);
WIRE 16 -1 (-2850 3825)(-2850 3775);
WIRE 16 -1 (-8050 3375)(-7175 3375);
WIRE 16 -1 (-8050 3375)(-8050 2975);
WIRE 16 -1 (-8575 3575)(-6150 3575);
WIRE 16 -1 (-8575 3575)(-8575 3475);
WIRE 16 -1 (-8575 3575)(-8800 3575);
FORCEPROP 2 LAST SIG_NAME PVDD18_S5_P0_EN
J 0
(-8760 3585);
DISPLAY 0.489362 (-8760 3585);
WIRE 16 -1 (-6725 4025)(-6725 3903);
WIRE 16 -1 (-6725 3903)(-6975 3903);
WIRE 16 -1 (-6975 4025)(-6975 3903);
WIRE 16 -1 (-7225 3903)(-6975 3903);
WIRE 16 -1 (-7225 4025)(-7225 3903);
WIRE 16 -1 (-7575 3903)(-7225 3903);
WIRE 16 -1 (-7575 4025)(-7575 3903);
WIRE 16 -1 (-7575 3903)(-7875 3903);
WIRE 16 -1 (-7875 4025)(-7875 3903);
WIRE 16 -1 (-7875 3903)(-7950 3903);
WIRE 16 -1 (-7950 3800)(-7950 3903);
WIRE 16 -1 (-8200 3903)(-7950 3903);
WIRE 16 -1 (-8200 4025)(-8200 3903);
WIRE 16 -1 (-6325 4025)(-6150 4025);
WIRE 16 -1 (-6325 4075)(-6325 4025);
WIRE 16 -1 (-6325 4350)(-6325 4075);
WIRE 16 -1 (-6325 4075)(-6150 4075);
WIRE 16 -1 (-6725 4350)(-6325 4350);
WIRE 16 -1 (-6725 4225)(-6725 4350);
WIRE 16 -1 (-6975 4350)(-6725 4350);
WIRE 16 -1 (-6975 4225)(-6975 4350);
WIRE 16 -1 (-7225 4350)(-6975 4350);
WIRE 16 -1 (-7225 4225)(-7225 4350);
WIRE 16 -1 (-7575 4350)(-7225 4350);
WIRE 16 -1 (-7575 4225)(-7575 4350);
WIRE 16 -1 (-7875 4350)(-7575 4350);
FORCEPROP 2 LAST SIG_NAME SW_P12V_AUX_PVDD18_S5_P0_FLT
J 0
(-7762 4373);
DISPLAY 0.489362 (-7762 4373);
FORCEPROP 2 LASTPROP $XRERR UNIQUE?
J 0
(-8002 4373);
DISPLAY 0.638298 (-8002 4373);
PAINT MONO (-8002 4373);
DISPLAY INVISIBLE (-8002 4373);
WIRE 16 -1 (-7875 4225)(-7875 4350);
WIRE 16 -1 (-8200 4350)(-7875 4350);
WIRE 16 -1 (-8200 4350)(-8200 4225);
WIRE 16 -1 (-8775 4350)(-8200 4350);
WIRE 17 273 (-1675 6500)(-100 6500);
WIRE 17 273 (-1675 6500)(-1675 5525);
WIRE 17 273 (-100 6500)(-100 5525);
WIRE 17 273 (-1675 5525)(-100 5525);
WIRE 16 -1 (-8975 4350)(-9225 4350);
WIRE 16 -1 (-9225 4500)(-9225 4350);
WIRE 16 -1 (-9225 4350)(-9225 4250);
WIRE 16 -1 (-3475 3575)(-2925 3575);
WIRE 16 -1 (-2925 3575)(-2475 3575);
WIRE 16 -1 (-2925 3425)(-2925 3575);
WIRE 16 -1 (-2475 3575)(-2275 3575);
WIRE 16 -1 (-2475 3425)(-2475 3575);
WIRE 16 -1 (-2275 3575)(-2025 3575);
WIRE 16 -1 (-2275 3425)(-2275 3575);
WIRE 16 -1 (-2025 3575)(-1700 3575);
WIRE 16 -1 (-2025 3575)(-2025 3425);
WIRE 16 -1 (-1425 3575)(-1700 3575);
WIRE 16 -1 (-1700 3575)(-1700 3425);
WIRE 16 -1 (-1425 3575)(-1100 3575);
WIRE 16 -1 (-1425 3575)(-1425 3425);
WIRE 16 -1 (-500 3575)(-1100 3575);
WIRE 16 -1 (-1100 3575)(-1100 3475);
WIRE 16 -1 (-1100 3475)(-700 3475);
WIRE 16 -1 (-1100 3475)(-1100 3425);
WIRE 16 -1 (-500 3575)(-500 3900);
WIRE 16 -1 (-500 3400)(-500 3575);
WIRE 16 -1 (-700 3475)(-700 2825);
WIRE 16 -1 (-700 2825)(-1600 2825);
WIRE 16 -1 (-2925 3225)(-2925 3075);
WIRE 16 -1 (-2475 3075)(-2925 3075);
WIRE 16 -1 (-2475 3075)(-2275 3075);
WIRE 16 -1 (-2475 3225)(-2475 3075);
WIRE 16 -1 (-2275 3075)(-2025 3075);
WIRE 16 -1 (-2275 3225)(-2275 3075);
WIRE 16 -1 (-2025 3075)(-1700 3075);
WIRE 16 -1 (-2025 3225)(-2025 3075);
WIRE 16 -1 (-1425 3075)(-1700 3075);
WIRE 16 -1 (-1700 3225)(-1700 3075);
WIRE 16 -1 (-1100 3075)(-1425 3075);
WIRE 16 -1 (-1425 3075)(-1425 3225);
WIRE 16 -1 (-1100 3075)(-1100 3225);
WIRE 16 -1 (-1100 3000)(-1100 3075);
WIRE 16 -1 (-5125 2775)(-5350 2775);
WIRE 16 -1 (-5125 2725)(-5125 2775);
WIRE 16 -1 (-5350 2725)(-5125 2725);
WIRE 16 -1 (-5125 2500)(-5125 2725);
WIRE 16 -1 (-5350 4075)(-4700 4075);
WIRE 16 -1 (-4700 4075)(-3750 4075);
FORCEPROP 2 LAST SIG_NAME PWRGD_PVDD18_S5_P0
J 0
(-4385 4100);
DISPLAY 0.489362 (-4385 4100);
FORCEPROP 2 LASTPROP $XRERR UNIQUE?
J 0
(-4625 4100);
DISPLAY 0.638298 (-4625 4100);
PAINT MONO (-4625 4100);
DISPLAY INVISIBLE (-4625 4100);
WIRE 16 -1 (-4700 4275)(-4700 4075);
WIRE 16 -1 (-4100 3625)(-4100 3575);
WIRE 16 -1 (-4100 3575)(-3675 3575);
WIRE 16 -1 (-5350 3575)(-4100 3575);
FORCEPROP 2 LAST SIG_NAME SW_PVDD18_S5_P0_SW
J 0
(-5245 3592);
DISPLAY 0.489362 (-5245 3592);
FORCEPROP 2 LASTPROP $XRERR UNIQUE?
J 0
(-5485 3592);
DISPLAY 0.638298 (-5485 3592);
PAINT MONO (-5485 3592);
DISPLAY INVISIBLE (-5485 3592);
WIRE 16 -1 (-6700 2775)(-6150 2775);
WIRE 16 -1 (-6700 2650)(-6700 2775);
FORCEPROP 2 LAST SIG_NAME PVDD18_S5_P0_CS
J 0
(-6560 2800);
DISPLAY 0.489362 (-6560 2800);
FORCEPROP 2 LASTPROP $XRERR UNIQUE?
J 0
(-6800 2800);
DISPLAY 0.638298 (-6800 2800);
PAINT MONO (-6800 2800);
DISPLAY INVISIBLE (-6800 2800);
WIRE 16 -1 (-5000 2875)(-4675 2875);
WIRE 16 -1 (-5000 2800)(-5000 2875);
WIRE 16 -1 (-5000 2875)(-5350 2875);
FORCEPROP 2 LAST SIG_NAME PVDD18_S5_P0_REF
J 0
(-5260 2885);
DISPLAY 0.489362 (-5260 2885);
FORCEPROP 2 LASTPROP $XRERR UNIQUE?
J 0
(-5500 2885);
DISPLAY 0.638298 (-5500 2885);
PAINT MONO (-5500 2885);
DISPLAY INVISIBLE (-5500 2885);
WIRE 16 -1 (-3607 2222)(-3607 2223);
WIRE 17 273 (-2025 2425)(-1150 2425);
WIRE 17 273 (-2025 2425)(-2025 1900);
WIRE 17 273 (-1150 2425)(-1150 1900);
WIRE 17 273 (-2025 1900)(-1150 1900);
WIRE 16 -1 (-2650 4075)(-2850 4075);
WIRE 16 -1 (-2850 4025)(-2850 4075);
WIRE 16 -1 (-2850 4075)(-3550 4075);
FORCEPROP 2 LAST SIG_NAME FM_PWRGD_PVDD18_S5_P0
J 0
(-3335 4100);
DISPLAY 0.489362 (-3335 4100);
WIRE 16 -1 (-2619 2251)(-2619 2252);
WIRE 16 -1 (-2500 2325)(-1450 2325);
FORCEPROP 2 LAST SIG_NAME VSENSE_PVDD18_S5_P0_DP
J 0
(-1985 2335);
DISPLAY 0.489362 (-1985 2335);
WIRE 16 -1 (-2500 2025)(-1450 2025);
FORCEPROP 2 LAST SIG_NAME VSENSE_PVDD18_S5_P0_DN
J 0
(-1985 2035);
DISPLAY 0.489362 (-1985 2035);
WIRE 17 273 (-2875 1575)(-750 1575);
WIRE 17 273 (-2875 2500)(-2875 1575);
WIRE 17 273 (-750 2500)(-750 1575);
WIRE 17 273 (-2875 2500)(-750 2500);
WIRE 16 -1 (-3250 3125)(-3150 3125);
WIRE 16 -1 (-3475 3125)(-3250 3125);
WIRE 16 -1 (-3250 3125)(-3250 2800);
WIRE 16 -1 (-3150 3125)(-3000 3125);
WIRE 16 -1 (-3150 2325)(-3150 3125);
WIRE 16 -1 (-3150 2325)(-2700 2325);
WIRE 16 -1 (-3150 2275)(-3150 2325);
WIRE 16 -1 (-3000 3125)(-3000 2825);
WIRE 16 -1 (-3250 2800)(-3475 2800);
WIRE 16 -1 (-3000 2825)(-1800 2825);
FORCEPROP 2 LAST SIG_NAME PVDD18_S5_P0_FB_RC
J 0
(-2860 2835);
DISPLAY 0.489362 (-2860 2835);
FORCEPROP 2 LASTPROP $XRERR UNIQUE?
J 0
(-3100 2835);
DISPLAY 0.638298 (-3100 2835);
PAINT MONO (-3100 2835);
DISPLAY INVISIBLE (-3100 2835);
WIRE 16 -1 (-7575 2650)(-7575 2775);
WIRE 16 -1 (-7575 2775)(-7025 2775);
WIRE 16 -1 (-7575 2875)(-7575 2775);
WIRE 16 -1 (-7025 2775)(-7025 3125);
WIRE 16 -1 (-6150 3125)(-7025 3125);
FORCEPROP 2 LAST SIG_NAME PVDD18_S5_P0_VCC
J 0
(-6610 3135);
DISPLAY 0.489362 (-6610 3135);
FORCEPROP 2 LASTPROP $XRERR UNIQUE?
J 0
(-6850 3135);
DISPLAY 0.638298 (-6850 3135);
PAINT MONO (-6850 3135);
DISPLAY INVISIBLE (-6850 3135);
WIRE 16 -1 (-6975 3375)(-6150 3375);
FORCEPROP 2 LAST SIG_NAME PVDD18_S5_P0_MODE
J 0
(-6810 3385);
DISPLAY 0.489362 (-6810 3385);
FORCEPROP 2 LASTPROP $XRERR UNIQUE?
J 0
(-7050 3385);
DISPLAY 0.638298 (-7050 3385);
PAINT MONO (-7050 3385);
DISPLAY INVISIBLE (-7050 3385);
WIRE 17 273 (-9175 1300)(-7000 1300);
WIRE 17 273 (-9175 1300)(-9175 700);
WIRE 17 273 (-7000 1300)(-7000 700);
WIRE 17 273 (-9175 700)(-7000 700);
WIRE 17 273 (-9175 1850)(-7000 1850);
WIRE 17 273 (-9175 1850)(-9175 1375);
WIRE 17 273 (-7000 1850)(-7000 1375);
WIRE 17 273 (-9175 1375)(-7000 1375);
WIRE 16 -1 (-2700 2025)(-3150 2025);
WIRE 16 -1 (-3150 2075)(-3150 2025);
WIRE 16 -1 (-3575 2025)(-3150 2025);
WIRE 16 -1 (-3575 2025)(-3575 1875);
WIRE 16 -1 (-3575 2025)(-4150 2025);
WIRE 16 -1 (-4150 2500)(-4150 2025);
WIRE 16 -1 (-4350 2025)(-4150 2025);
WIRE 16 -1 (-4350 2875)(-4350 2025);
WIRE 16 -1 (-4350 2975)(-4350 2875);
WIRE 16 -1 (-4475 2875)(-4350 2875);
WIRE 16 -1 (-5350 2975)(-4350 2975);
FORCEPROP 2 LAST SIG_NAME PVDD18_S5_P0_RGND
J 0
(-5260 2985);
DISPLAY 0.489362 (-5260 2985);
FORCEPROP 2 LASTPROP $XRERR UNIQUE?
J 0
(-5500 2985);
DISPLAY 0.638298 (-5500 2985);
PAINT MONO (-5500 2985);
DISPLAY INVISIBLE (-5500 2985);
WIRE 16 -1 (-3675 2800)(-3875 2800);
WIRE 16 -1 (-3875 3125)(-3875 2800);
WIRE 16 -1 (-3675 3125)(-3875 3125);
WIRE 16 -1 (-3875 3125)(-4150 3125);
WIRE 16 -1 (-4150 2700)(-4150 3125);
WIRE 16 -1 (-5350 3125)(-4150 3125);
FORCEPROP 2 LAST SIG_NAME PVDD18_S5_P0_FB
J 0
(-5251 3139);
DISPLAY 0.489362 (-5251 3139);
FORCEPROP 2 LASTPROP $XRERR UNIQUE?
J 0
(-5491 3139);
DISPLAY 0.638298 (-5491 3139);
PAINT MONO (-5491 3139);
DISPLAY INVISIBLE (-5491 3139);
WIRE 16 -1 (-5350 3875)(-4650 3875);
FORCEPROP 2 LAST SIG_NAME SW_PVDD18_S5_P0_BST
J 0
(-5260 3900);
DISPLAY 0.489362 (-5260 3900);
FORCEPROP 2 LASTPROP $XRERR UNIQUE?
J 0
(-5500 3900);
DISPLAY 0.638298 (-5500 3900);
PAINT MONO (-5500 3900);
DISPLAY INVISIBLE (-5500 3900);
WIRE 16 -1 (-4100 3825)(-4100 3875);
WIRE 16 -1 (-4100 3875)(-4450 3875);
FORCEPROP 2 LAST SIG_NAME SW_PVDD18_S5_P0_BST_R
J 0
(-4435 3885);
DISPLAY 0.361702 (-4435 3885);
FORCEPROP 2 LASTPROP $XRERR UNIQUE?
J 0
(-4675 3885);
DISPLAY 0.638298 (-4675 3885);
PAINT MONO (-4675 3885);
DISPLAY INVISIBLE (-4675 3885);
DOT 1 (-4700 4075);
DOT 1 (-4100 3575);
DOT 1 (-7575 4350);
DOT 1 (-8575 3575);
DOT 1 (-9225 4350);
DOT 1 (-7575 2775);
DOT 1 (-5125 2725);
DOT 1 (-5000 2875);
DOT 1 (-4150 2025);
DOT 1 (-4350 2875);
DOT 1 (-4150 3125);
DOT 1 (-6725 4350);
DOT 1 (-6325 4075);
DOT 1 (-3575 2025);
DOT 1 (-3150 2025);
DOT 1 (-3150 2325);
DOT 1 (-3875 3125);
DOT 1 (-3150 3125);
DOT 1 (-3250 3125);
DOT 1 (-2925 3575);
DOT 1 (-2475 3075);
DOT 1 (-2275 3075);
DOT 1 (-2275 3575);
DOT 1 (-2025 3075);
DOT 1 (-1700 3075);
DOT 1 (-2025 3575);
DOT 1 (-1700 3575);
DOT 1 (-1425 3075);
DOT 1 (-1100 3075);
DOT 1 (-1100 3475);
DOT 1 (-1425 3575);
DOT 1 (-1100 3575);
DOT 1 (-500 3575);
DOT 1 (-2475 3575);
DOT 1 (-2850 4075);
DOT 1 (-6975 4350);
DOT 1 (-6975 3903);
DOT 1 (-7225 4350);
DOT 1 (-7575 3903);
DOT 1 (-7875 4350);
DOT 1 (-7875 3903);
DOT 1 (-7225 3903);
DOT 1 (-7950 3903);
DOT 1 (-8200 4350);
FORCENOTE
FSW=600KHZ
(-8725 2850) 0;
DISPLAY LEFT (-8725 2850);
DISPLAY 1.276596 (-8725 2850);
PAINT WHITE (-8725 2850);
FORCENOTE
EFFICIENCY > 85% @TDC
(-1650 5625) 0;
DISPLAY LEFT (-1650 5625);
DISPLAY 0.936170 (-1650 5625);
PAINT WHITE (-1650 5625);
FORCENOTE
PVDD18_S5_P0
(-6175 5475) 0;
DISPLAY LEFT (-6175 5475);
DISPLAY 3.148936 (-6175 5475);
PAINT WHITE (-6175 5475);
FORCENOTE
MAX LOAD STEP=2.5A
(-1650 5850) 0;
DISPLAY LEFT (-1650 5850);
DISPLAY 0.936170 (-1650 5850);
PAINT WHITE (-1650 5850);
FORCENOTE
WORK FREQUENCY=600KHZ
(-1650 5700) 0;
DISPLAY LEFT (-1650 5700);
DISPLAY 0.936170 (-1650 5700);
PAINT WHITE (-1650 5700);
FORCENOTE
IRM REV1.09
(-1650 5550) 0;
DISPLAY LEFT (-1650 5550);
DISPLAY 0.936170 (-1650 5550);
PAINT WHITE (-1650 5550);
FORCENOTE
MAX LOAD RELEASE=2.5A
(-1650 5775) 0;
DISPLAY LEFT (-1650 5775);
DISPLAY 0.936170 (-1650 5775);
PAINT WHITE (-1650 5775);
FORCENOTE
AC =+/-30MV
(-1650 6150) 0;
DISPLAY LEFT (-1650 6150);
DISPLAY 0.936170 (-1650 6150);
PAINT WHITE (-1650 6150);
FORCENOTE
EDC=12A
(-1650 6000) 0;
DISPLAY LEFT (-1650 6000);
DISPLAY 0.936170 (-1650 6000);
PAINT WHITE (-1650 6000);
FORCENOTE
OUTPUT VOLTAGE=1.8V
(-1650 6300) 0;
DISPLAY LEFT (-1650 6300);
DISPLAY 0.936170 (-1650 6300);
PAINT WHITE (-1650 6300);
FORCENOTE
OCP=15A (EDC*1.2)
(-1650 5925) 0;
DISPLAY LEFT (-1650 5925);
DISPLAY 0.936170 (-1650 5925);
PAINT WHITE (-1650 5925);
FORCENOTE
RB
(-4275 2575) 0;
DISPLAY LEFT (-4275 2575);
DISPLAY 1.021277 (-4275 2575);
PAINT WHITE (-4275 2575);
FORCENOTE
FCCM
(-8725 2950) 0;
DISPLAY LEFT (-8725 2950);
DISPLAY 1.276596 (-8725 2950);
PAINT WHITE (-8725 2950);
FORCENOTE
VOUT=0.6(1+RA/RB)=1.8V
(-5725 1750) 0;
DISPLAY LEFT (-5725 1750);
DISPLAY 2.000000 (-5725 1750);
PAINT WHITE (-5725 1750);
FORCENOTE
DIFFERENTIAL PAIR
(-1725 1800) 0;
DISPLAY LEFT (-1725 1800);
DISPLAY 1.021277 (-1725 1800);
PAINT WHITE (-1725 1800);
FORCENOTE
TRACE WIDTH = 10MIL
(-1725 1725) 0;
DISPLAY LEFT (-1725 1725);
DISPLAY 1.021277 (-1725 1725);
PAINT WHITE (-1725 1725);
FORCENOTE
5.0*5.8
(-1550 2975) 0;
DISPLAY LEFT (-1550 2975);
DISPLAY 0.510638 (-1550 2975);
FORCENOTE
2ND=CC7390JMZ11
(-1550 2925) 0;
DISPLAY LEFT (-1550 2925);
DISPLAY 0.510638 (-1550 2925);
PAINT WHITE (-1550 2925);
FORCENOTE
ESR=10M OHM
(-1550 3025) 0;
DISPLAY LEFT (-1550 3025);
DISPLAY 0.510638 (-1550 3025);
FORCENOTE
DC =1.76-1.84V
(-1650 6225) 0;
DISPLAY LEFT (-1650 6225);
DISPLAY 0.936170 (-1650 6225);
PAINT WHITE (-1650 6225);
FORCENOTE
TDC=10A
(-1650 6075) 0;
DISPLAY LEFT (-1650 6075);
DISPLAY 0.936170 (-1650 6075);
PAINT WHITE (-1650 6075);
FORCENOTE
PVDD18_S5_P0 SPECFICATION
(-1650 6425) 0;
DISPLAY LEFT (-1650 6425);
DISPLAY 1.276596 (-1650 6425);
PAINT WHITE (-1650 6425);
FORCENOTE
TRACE SPACING = 5MIL
(-1725 1650) 0;
DISPLAY LEFT (-1725 1650);
DISPLAY 1.021277 (-1725 1650);
PAINT WHITE (-1725 1650);
FORCENOTE
RA
(-3625 3225) 0;
DISPLAY LEFT (-3625 3225);
DISPLAY 1.021277 (-3625 3225);
PAINT WHITE (-3625 3225);
FORCENOTE
NEAR CPU SIDE
(-2850 1600) 0;
DISPLAY LEFT (-2850 1600);
DISPLAY 1.021277 (-2850 1600);
PAINT GREEN (-2850 1600);
FORCENOTE
DCR=5M OHM
(-9000 4225) 0;
DISPLAY LEFT (-9000 4225);
DISPLAY 0.808511 (-9000 4225);
PAINT WHITE (-9000 4225);
FORCENOTE
1ST
(-9100 1050) 0;
DISPLAY LEFT (-9100 1050);
DISPLAY 1.021277 (-9100 1050);
PAINT WHITE (-9100 1050);
FORCENOTE
BOM NOTE
(-9100 1750) 0;
DISPLAY LEFT (-9100 1750);
DISPLAY 1.276596 (-9100 1750);
PAINT WHITE (-9100 1750);
FORCENOTE
3RD AL000548007/TPS548B28RWWR/TI
(-9100 1450) 0;
DISPLAY LEFT (-9100 1450);
DISPLAY 1.021277 (-9100 1450);
PAINT WHITE (-9100 1450);
FORCENOTE
2ND AL053319002/RS53319LR/REEDSEMI
(-9100 1525) 0;
DISPLAY LEFT (-9100 1525);
DISPLAY 1.021277 (-9100 1525);
PAINT WHITE (-9100 1525);
FORCENOTE
1ST AL008633005/MPQ8633BGLE-C838-Z/MPS
(-9100 1600) 0;
DISPLAY LEFT (-9100 1600);
DISPLAY 1.021277 (-9100 1600);
PAINT WHITE (-9100 1600);
FORCENOTE
3RD PC212 CHANGE TO CH5222KEB01
(-9100 850) 0;
DISPLAY LEFT (-9100 850);
DISPLAY 1.021277 (-9100 850);
PAINT WHITE (-9100 850);
FORCENOTE
PC259 CHANGE TO CH13306JB14
(-8900 775) 0;
DISPLAY LEFT (-8900 775);
DISPLAY 1.021277 (-8900 775);
PAINT WHITE (-8900 775);
FORCENOTE
BOM CHANGE R&C TABLE
(-9100 1200) 0;
DISPLAY LEFT (-9100 1200);
DISPLAY 1.276596 (-9100 1200);
PAINT WHITE (-9100 1200);
FORCENOTE
2ND  NA
(-9100 950) 0;
DISPLAY LEFT (-9100 950);
DISPLAY 1.021277 (-9100 950);
PAINT WHITE (-9100 950);
FORCENOTE
3RD=CX000220000
(-9000 4125) 0;
DISPLAY LEFT (-9000 4125);
DISPLAY 0.808511 (-9000 4125);
PAINT WHITE (-9000 4125);
FORCENOTE
2ND=CX220Z06Z00
(-9000 4175) 0;
DISPLAY LEFT (-9000 4175);
DISPLAY 0.808511 (-9000 4175);
PAINT WHITE (-9000 4175);
FORCENOTE
IRATED=5A@125C
(-9000 4275) 0;
DISPLAY LEFT (-9000 4275);
DISPLAY 0.808511 (-9000 4275);
PAINT WHITE (-9000 4275);
FORCENOTE
10*10*4
(-3400 3750) 0;
DISPLAY LEFT (-3400 3750);
DISPLAY 0.638298 (-3400 3750);
PAINT WHITE (-3400 3750);
FORCENOTE
DCR=3.3M OHM
(-3400 3700) 0;
DISPLAY LEFT (-3400 3700);
DISPLAY 0.638298 (-3400 3700);
PAINT WHITE (-3400 3700);
FORCENOTE
ISAT:25A@100C
(-3400 3800) 0;
DISPLAY LEFT (-3400 3800);
DISPLAY 0.638298 (-3400 3800);
PAINT WHITE (-3400 3800);
FORCENOTE
PCMC104T-1R0MN
(-3400 3850) 0;
DISPLAY LEFT (-3400 3850);
DISPLAY 0.638298 (-3400 3850);
PAINT WHITE (-3400 3850);
FORCENOTE
2ND=CV-10I0MZ00
(-3400 3650) 0;
DISPLAY LEFT (-3400 3650);
DISPLAY 0.638298 (-3400 3650);
PAINT WHITE (-3400 3650);
QUIT
